FILE_TYPE = MACRO_DRAWING;
SET COLOR_WIRE YELLOW;
SET COLOR_PROP MONO;
SET COLOR_DOT WHITE;
SET COLOR_ARC YELLOW;
SET COLOR_BODY GREEN;
SET COLOR_NOTE MONO;
SET PROP_DISPLAY VALUE;
SET PAGE_NUMBER P104;
FORCEADD OFFPAGE..1
(-525 2000);
FORCEPROP 2 LAST $XR0 190 
J 0
(-777 2000);
DISPLAY 0.638298 (-777 2000);
PAINT MONO (-777 2000);
FORCEPROP 2 LAST CDS_LIB mstr_standard
J 0
(-525 2000);
PAINT ORANGE (-525 2000);
DISPLAY INVISIBLE (-525 2000);
FORCEPROP 1 LAST COMMENT_BODY TRUE
J 0
(-400 1900);
DISPLAY 0.872340 (-400 1900);
PAINT GREEN (-400 1900);
DISPLAY INVISIBLE (-400 1900);
FORCEPROP 1 LAST OFFPAGE TRUE
J 0
(-200 1875);
DISPLAY 0.872340 (-200 1875);
PAINT GREEN (-200 1875);
DISPLAY INVISIBLE (-200 1875);
FORCEPROP 2 LAST PATH I100
J 0
(-475 2075);
DISPLAY 1.021277 (-475 2075);
PAINT ORANGE (-475 2075);
DISPLAY INVISIBLE (-475 2075);
FORCEADD OFFPAGE..1
(-525 1500);
FORCEPROP 2 LAST $XR0 190 
J 0
(-777 1500);
DISPLAY 0.638298 (-777 1500);
PAINT MONO (-777 1500);
FORCEPROP 2 LAST CDS_LIB mstr_standard
J 0
(-525 1500);
PAINT ORANGE (-525 1500);
DISPLAY INVISIBLE (-525 1500);
FORCEPROP 2 LAST PATH I101
J 0
(-475 1575);
DISPLAY 1.021277 (-475 1575);
PAINT ORANGE (-475 1575);
DISPLAY INVISIBLE (-475 1575);
FORCEPROP 1 LAST COMMENT_BODY TRUE
J 0
(-400 1400);
DISPLAY 0.872340 (-400 1400);
PAINT GREEN (-400 1400);
DISPLAY INVISIBLE (-400 1400);
FORCEPROP 1 LAST OFFPAGE TRUE
J 0
(-200 1375);
DISPLAY 0.872340 (-200 1375);
PAINT GREEN (-200 1375);
DISPLAY INVISIBLE (-200 1375);
FORCEADD OFFPAGE..1
(-525 1300);
FORCEPROP 2 LAST $XR0 191 
J 0
(-777 1300);
DISPLAY 0.638298 (-777 1300);
PAINT MONO (-777 1300);
FORCEPROP 2 LAST CDS_LIB mstr_standard
J 0
(-525 1300);
PAINT ORANGE (-525 1300);
DISPLAY INVISIBLE (-525 1300);
FORCEPROP 2 LAST PATH I102
J 0
(-475 1375);
DISPLAY 1.021277 (-475 1375);
PAINT ORANGE (-475 1375);
DISPLAY INVISIBLE (-475 1375);
FORCEPROP 1 LAST COMMENT_BODY TRUE
J 0
(-400 1200);
DISPLAY 0.872340 (-400 1200);
PAINT GREEN (-400 1200);
DISPLAY INVISIBLE (-400 1200);
FORCEPROP 1 LAST OFFPAGE TRUE
J 0
(-200 1175);
DISPLAY 0.872340 (-200 1175);
PAINT GREEN (-200 1175);
DISPLAY INVISIBLE (-200 1175);
FORCEADD RES..1
(550 1800);
FORCEPROP 1 LAST VALUE 0.0
J 1
(325 1750);
DISPLAY 0.617021 (325 1750);
PAINT SKYBLUE (325 1750);
FORCEPROP 1 LAST TOLERANCE 5%
J 0
(525 1750);
DISPLAY 0.617021 (525 1750);
PAINT SKYBLUE (525 1750);
FORCEPROP 1 LASTPIN (450 1800) $PN 1
J 0
(462 1812);
DISPLAY 0.617021 (462 1812);
PAINT ORANGE (462 1812);
FORCEPROP 1 LAST PACK_TYPE 0402
J 1
(800 1750);
DISPLAY 0.617021 (800 1750);
PAINT SKYBLUE (800 1750);
FORCEPROP 1 LAST WATTAGE 1/16W
J 0
(375 1750);
DISPLAY 0.617021 (375 1750);
PAINT SKYBLUE (375 1750);
FORCEPROP 1 LAST PART_NUMBER G21497-005
J 0
(675 1800);
DISPLAY 0.617021 (675 1800);
PAINT BLUE (675 1800);
FORCEPROP 1 LAST MATERIAL CHIP
J 1
(675 1750);
DISPLAY 0.617021 (675 1750);
PAINT SKYBLUE (675 1750);
FORCEPROP 1 LASTPIN (650 1800) $PN 2
J 0
(612 1812);
DISPLAY 0.617021 (612 1812);
PAINT ORANGE (612 1812);
FORCEPROP 1 LAST LOCATION R7D39
J 0
(500 1850);
DISPLAY 0.617021 (500 1850);
PAINT AQUA (500 1850);
FORCEPROP 1 LAST PATH I103
J 0
(500 1950);
DISPLAY 0.978723 (500 1950);
PAINT WHITE (500 1950);
DISPLAY INVISIBLE (500 1950);
FORCEPROP 2 LAST CDS_LIB mstr_discrete
J 0
(550 1800);
PAINT ORANGE (550 1800);
DISPLAY INVISIBLE (550 1800);
FORCEPROP 2 LAST SEC_TYPE 0402
J 0
(500 2000);
DISPLAY 1.021277 (500 2000);
PAINT ORANGE (500 2000);
DISPLAY INVISIBLE (500 2000);
FORCEPROP 2 LAST SEC 1
J 0
(500 2000);
DISPLAY 0.680851 (500 2000);
PAINT MONO (500 2000);
DISPLAY INVISIBLE (500 2000);
FORCEPROP 0 LAST ROOM CLOCK_CPU1_OSC
J 0
(500 1950);
DISPLAY 1.021277 (500 1950);
PAINT ORANGE (500 1950);
DISPLAY INVISIBLE (500 1950);
FORCEPROP 0 LAST NO_XNET_CONNECTION 1
J 0
(500 2000);
PAINT MONO (500 2000);
DISPLAY INVISIBLE (500 2000);
FORCEPROP 2 LAST CDS_LOCATION R7D39
J 0
(500 1850);
DISPLAY 0.617021 (500 1850);
PAINT AQUA (500 1850);
DISPLAY INVISIBLE (500 1850);
FORCEADD RES..1
(550 1100);
FORCEPROP 1 LAST LOCATION R7D37
J 0
(500 1150);
DISPLAY 0.617021 (500 1150);
PAINT AQUA (500 1150);
FORCEPROP 1 LASTPIN (650 1100) $PN 2
J 0
(612 1112);
DISPLAY 0.617021 (612 1112);
PAINT ORANGE (612 1112);
FORCEPROP 1 LAST VALUE 0.0
J 1
(325 1050);
DISPLAY 0.617021 (325 1050);
PAINT SKYBLUE (325 1050);
FORCEPROP 1 LAST TOLERANCE 5%
J 0
(525 1050);
DISPLAY 0.617021 (525 1050);
PAINT SKYBLUE (525 1050);
FORCEPROP 1 LAST MATERIAL CHIP
J 1
(675 1050);
DISPLAY 0.617021 (675 1050);
PAINT SKYBLUE (675 1050);
FORCEPROP 1 LASTPIN (450 1100) $PN 1
J 0
(462 1112);
DISPLAY 0.617021 (462 1112);
PAINT ORANGE (462 1112);
FORCEPROP 1 LAST PACK_TYPE 0402
J 1
(800 1050);
DISPLAY 0.617021 (800 1050);
PAINT SKYBLUE (800 1050);
FORCEPROP 1 LAST WATTAGE 1/16W
J 0
(375 1050);
DISPLAY 0.617021 (375 1050);
PAINT SKYBLUE (375 1050);
FORCEPROP 1 LAST PART_NUMBER G21497-005
J 0
(675 1100);
DISPLAY 0.617021 (675 1100);
PAINT BLUE (675 1100);
FORCEPROP 1 LAST PATH I104
J 0
(500 1250);
DISPLAY 0.978723 (500 1250);
PAINT WHITE (500 1250);
DISPLAY INVISIBLE (500 1250);
FORCEPROP 2 LAST CDS_LIB mstr_discrete
J 0
(550 1100);
PAINT ORANGE (550 1100);
DISPLAY INVISIBLE (550 1100);
FORCEPROP 2 LAST SEC_TYPE 0402
J 0
(500 1300);
DISPLAY 1.021277 (500 1300);
PAINT ORANGE (500 1300);
DISPLAY INVISIBLE (500 1300);
FORCEPROP 2 LAST SEC 1
J 0
(500 1300);
DISPLAY 0.680851 (500 1300);
PAINT MONO (500 1300);
DISPLAY INVISIBLE (500 1300);
FORCEPROP 0 LAST ROOM CLOCK_CPU1_OSC
J 0
(500 1250);
DISPLAY 1.021277 (500 1250);
PAINT ORANGE (500 1250);
DISPLAY INVISIBLE (500 1250);
FORCEPROP 0 LAST NO_XNET_CONNECTION 1
J 0
(500 1300);
PAINT MONO (500 1300);
DISPLAY INVISIBLE (500 1300);
FORCEPROP 2 LAST CDS_LOCATION R7D37
J 0
(500 1150);
DISPLAY 0.617021 (500 1150);
PAINT AQUA (500 1150);
DISPLAY INVISIBLE (500 1150);
FORCEADD P3V3..1
(-3975 5350);
FORCEPROP 3 LASTPIN (-3975 5300) SIG_NAME P3V3\g
J 0
(-3965 5310);
DISPLAY 0.659574 (-3965 5310);
PAINT MONO (-3965 5310);
DISPLAY INVISIBLE (-3965 5310);
FORCEPROP 1 LAST HDL_POWER P3V3
J 0
(-4300 5225);
DISPLAY 0.872340 (-4300 5225);
PAINT ORANGE (-4300 5225);
DISPLAY INVISIBLE (-4300 5225);
FORCEPROP 1 LAST BODY_TYPE PLUMBING
J 0
(-4020 5307);
DISPLAY 0.340426 (-4020 5307);
PAINT GREEN (-4020 5307);
DISPLAY INVISIBLE (-4020 5307);
FORCEPROP 1 LAST VOLTAGE 3.3V
J 0
(-4020 5307);
DISPLAY 0.340426 (-4020 5307);
PAINT SKYBLUE (-4020 5307);
DISPLAY INVISIBLE (-4020 5307);
FORCEPROP 1 LAST PATH I24
J 0
(-3930 5352);
DISPLAY 0.340426 (-3930 5352);
PAINT GREEN (-3930 5352);
DISPLAY INVISIBLE (-3930 5352);
FORCEPROP 2 LAST CDS_LIB mstr_symbols
J 0
(-3975 5350);
PAINT ORANGE (-3975 5350);
DISPLAY INVISIBLE (-3975 5350);
FORCEPROP 1 LAST SIZE 1B
J 0
(-3930 5372);
DISPLAY 0.340426 (-3930 5372);
PAINT GREEN (-3930 5372);
DISPLAY INVISIBLE (-3930 5372);
FORCEADD CAP_A..1
(-4250 5100);
FORCEPROP 1 LASTPIN (-4250 5000) $PN 2
J 0
(-4240 4980);
DISPLAY 0.617021 (-4240 4980);
PAINT ORANGE (-4240 4980);
FORCEPROP 1 LAST TOLERANCE 10%
J 0
(-4200 5050);
DISPLAY 0.617021 (-4200 5050);
PAINT SKYBLUE (-4200 5050);
FORCEPROP 1 LAST MATERIAL X7R
J 0
(-4200 5000);
DISPLAY 0.617021 (-4200 5000);
PAINT SKYBLUE (-4200 5000);
FORCEPROP 1 LAST VOLTAGE 16V
J 0
(-4200 5100);
DISPLAY 0.617021 (-4200 5100);
PAINT SKYBLUE (-4200 5100);
FORCEPROP 1 LASTPIN (-4250 5200) $PN 1
J 0
(-4240 5180);
DISPLAY 0.617021 (-4240 5180);
PAINT ORANGE (-4240 5180);
FORCEPROP 1 LAST LOCATION C6F1
J 0
(-4200 5200);
DISPLAY 0.617021 (-4200 5200);
PAINT AQUA (-4200 5200);
FORCEPROP 1 LAST VALUE 0.1UF
J 0
(-4200 5150);
DISPLAY 0.617021 (-4200 5150);
PAINT SKYBLUE (-4200 5150);
FORCEPROP 1 LAST PACK_TYPE 0402V
J 0
(-4200 4900);
DISPLAY 0.617021 (-4200 4900);
PAINT SKYBLUE (-4200 4900);
FORCEPROP 1 LAST PART_NUMBER A36096-030
J 0
(-4200 4950);
DISPLAY 0.617021 (-4200 4950);
PAINT BLUE (-4200 4950);
FORCEPROP 2 LAST CDS_LIB dev_discrete
J 0
(-4250 5100);
PAINT ORANGE (-4250 5100);
DISPLAY INVISIBLE (-4250 5100);
FORCEPROP 1 LAST PATH I25
J 0
(-4200 5250);
DISPLAY 0.978723 (-4200 5250);
PAINT WHITE (-4200 5250);
DISPLAY INVISIBLE (-4200 5250);
FORCEPROP 0 LAST ROOM CLOCK_CPU0_OSC
J 0
(-4200 5300);
DISPLAY 1.021277 (-4200 5300);
PAINT ORANGE (-4200 5300);
DISPLAY INVISIBLE (-4200 5300);
FORCEPROP 2 LAST CDS_SEC 1
J 0
(-4200 5250);
PAINT ORANGE (-4200 5250);
DISPLAY INVISIBLE (-4200 5250);
FORCEPROP 2 LAST SEC_TYPE 0402V
J 0
(-4200 5300);
DISPLAY 1.021277 (-4200 5300);
PAINT ORANGE (-4200 5300);
DISPLAY INVISIBLE (-4200 5300);
FORCEPROP 2 LAST SEC 1
J 0
(-4200 5300);
DISPLAY 0.680851 (-4200 5300);
PAINT MONO (-4200 5300);
DISPLAY INVISIBLE (-4200 5300);
FORCEPROP 2 LAST CDS_LOCATION C6F1
J 0
(-4200 5200);
DISPLAY 0.617021 (-4200 5200);
PAINT AQUA (-4200 5200);
DISPLAY INVISIBLE (-4200 5200);
FORCEADD GND..1
(-2725 4550);
FORCEPROP 3 LASTPIN (-2725 4600) SIG_NAME GND\g
J 0
(-2715 4610);
DISPLAY 0.659574 (-2715 4610);
PAINT MONO (-2715 4610);
DISPLAY INVISIBLE (-2715 4610);
FORCEPROP 1 LAST PATH I26
J 0
(-2650 4550);
DISPLAY 0.872340 (-2650 4550);
PAINT AQUA (-2650 4550);
DISPLAY INVISIBLE (-2650 4550);
FORCEPROP 1 LAST HDL_POWER GND
J 0
(-2725 4700);
DISPLAY 0.872340 (-2725 4700);
PAINT GREEN (-2725 4700);
DISPLAY INVISIBLE (-2725 4700);
FORCEPROP 1 LAST VOLTAGE 0.0V
J 0
(-2770 4507);
DISPLAY 0.340426 (-2770 4507);
PAINT SKYBLUE (-2770 4507);
DISPLAY INVISIBLE (-2770 4507);
FORCEPROP 2 LAST CDS_LIB mstr_symbols
J 0
(-2725 4550);
PAINT ORANGE (-2725 4550);
DISPLAY INVISIBLE (-2725 4550);
FORCEPROP 1 LAST BODY_TYPE PLUMBING
J 0
(-2770 4507);
DISPLAY 0.340426 (-2770 4507);
PAINT GREEN (-2770 4507);
DISPLAY INVISIBLE (-2770 4507);
FORCEPROP 1 LAST SIZE 1B
J 0
(-2650 4500);
DISPLAY 0.872340 (-2650 4500);
PAINT AQUA (-2650 4500);
DISPLAY INVISIBLE (-2650 4500);
FORCEADD GND..1
(-4250 4900);
FORCEPROP 3 LASTPIN (-4250 4950) SIG_NAME GND\g
J 0
(-4240 4960);
DISPLAY 0.659574 (-4240 4960);
PAINT MONO (-4240 4960);
DISPLAY INVISIBLE (-4240 4960);
FORCEPROP 1 LAST SIZE 1B
J 0
(-4175 4850);
DISPLAY 0.872340 (-4175 4850);
PAINT AQUA (-4175 4850);
DISPLAY INVISIBLE (-4175 4850);
FORCEPROP 1 LAST BODY_TYPE PLUMBING
J 0
(-4295 4857);
DISPLAY 0.340426 (-4295 4857);
PAINT GREEN (-4295 4857);
DISPLAY INVISIBLE (-4295 4857);
FORCEPROP 1 LAST VOLTAGE 0.0V
J 0
(-4295 4857);
DISPLAY 0.340426 (-4295 4857);
PAINT SKYBLUE (-4295 4857);
DISPLAY INVISIBLE (-4295 4857);
FORCEPROP 2 LAST CDS_LIB mstr_symbols
J 0
(-4250 4900);
PAINT ORANGE (-4250 4900);
DISPLAY INVISIBLE (-4250 4900);
FORCEPROP 1 LAST HDL_POWER GND
J 0
(-4250 5050);
DISPLAY 0.872340 (-4250 5050);
PAINT GREEN (-4250 5050);
DISPLAY INVISIBLE (-4250 5050);
FORCEPROP 1 LAST PATH I27
J 0
(-4175 4900);
DISPLAY 0.872340 (-4175 4900);
PAINT AQUA (-4175 4900);
DISPLAY INVISIBLE (-4175 4900);
FORCEADD OFFPAGE..1
(-4525 4775);
FORCEPROP 2 LAST $XR0 104 
J 0
(-4777 4775);
DISPLAY 0.638298 (-4777 4775);
PAINT MONO (-4777 4775);
FORCEPROP 1 LAST COMMENT_BODY TRUE
J 0
(-4400 4675);
DISPLAY 0.872340 (-4400 4675);
PAINT GREEN (-4400 4675);
DISPLAY INVISIBLE (-4400 4675);
FORCEPROP 2 LAST PATH I29
J 0
(-4475 4850);
DISPLAY 1.021277 (-4475 4850);
PAINT ORANGE (-4475 4850);
DISPLAY INVISIBLE (-4475 4850);
FORCEPROP 2 LAST CDS_LIB mstr_standard
J 0
(-4525 4775);
PAINT ORANGE (-4525 4775);
DISPLAY INVISIBLE (-4525 4775);
FORCEPROP 1 LAST OFFPAGE TRUE
J 0
(-4200 4650);
DISPLAY 0.872340 (-4200 4650);
PAINT GREEN (-4200 4650);
DISPLAY INVISIBLE (-4200 4650);
FORCEADD GND..1
(-3050 3700);
FORCEPROP 3 LASTPIN (-3050 3750) SIG_NAME GND\g
J 0
(-3040 3760);
DISPLAY 0.659574 (-3040 3760);
PAINT MONO (-3040 3760);
DISPLAY INVISIBLE (-3040 3760);
FORCEPROP 1 LAST VOLTAGE 0.0V
J 0
(-3095 3657);
DISPLAY 0.340426 (-3095 3657);
PAINT SKYBLUE (-3095 3657);
DISPLAY INVISIBLE (-3095 3657);
FORCEPROP 1 LAST BODY_TYPE PLUMBING
J 0
(-3095 3657);
DISPLAY 0.340426 (-3095 3657);
PAINT GREEN (-3095 3657);
DISPLAY INVISIBLE (-3095 3657);
FORCEPROP 2 LAST CDS_LIB mstr_symbols
J 0
(-3050 3700);
PAINT ORANGE (-3050 3700);
DISPLAY INVISIBLE (-3050 3700);
FORCEPROP 1 LAST PATH I31
J 0
(-2975 3700);
DISPLAY 0.872340 (-2975 3700);
PAINT AQUA (-2975 3700);
DISPLAY INVISIBLE (-2975 3700);
FORCEPROP 1 LAST SIZE 1B
J 0
(-2975 3650);
DISPLAY 0.872340 (-2975 3650);
PAINT AQUA (-2975 3650);
DISPLAY INVISIBLE (-2975 3650);
FORCEPROP 1 LAST HDL_POWER GND
J 0
(-3050 3850);
DISPLAY 0.872340 (-3050 3850);
PAINT GREEN (-3050 3850);
DISPLAY INVISIBLE (-3050 3850);
FORCEADD P3V3..1
(-4275 4475);
FORCEPROP 3 LASTPIN (-4275 4425) SIG_NAME P3V3\g
J 0
(-4265 4435);
DISPLAY 0.659574 (-4265 4435);
PAINT MONO (-4265 4435);
DISPLAY INVISIBLE (-4265 4435);
FORCEPROP 1 LAST HDL_POWER P3V3
J 0
(-4600 4350);
DISPLAY 0.872340 (-4600 4350);
PAINT ORANGE (-4600 4350);
DISPLAY INVISIBLE (-4600 4350);
FORCEPROP 1 LAST BODY_TYPE PLUMBING
J 0
(-4320 4432);
DISPLAY 0.340426 (-4320 4432);
PAINT GREEN (-4320 4432);
DISPLAY INVISIBLE (-4320 4432);
FORCEPROP 1 LAST VOLTAGE 3.3V
J 0
(-4320 4432);
DISPLAY 0.340426 (-4320 4432);
PAINT SKYBLUE (-4320 4432);
DISPLAY INVISIBLE (-4320 4432);
FORCEPROP 2 LAST CDS_LIB mstr_symbols
J 0
(-4275 4475);
PAINT ORANGE (-4275 4475);
DISPLAY INVISIBLE (-4275 4475);
FORCEPROP 1 LAST PATH I32
J 0
(-4230 4477);
DISPLAY 0.340426 (-4230 4477);
PAINT GREEN (-4230 4477);
DISPLAY INVISIBLE (-4230 4477);
FORCEPROP 1 LAST SIZE 1B
J 0
(-4230 4497);
DISPLAY 0.340426 (-4230 4497);
PAINT GREEN (-4230 4497);
DISPLAY INVISIBLE (-4230 4497);
FORCEADD GND..1
(-4575 4025);
FORCEPROP 3 LASTPIN (-4575 4075) SIG_NAME GND\g
J 0
(-4565 4085);
DISPLAY 0.659574 (-4565 4085);
PAINT MONO (-4565 4085);
DISPLAY INVISIBLE (-4565 4085);
FORCEPROP 1 LAST BODY_TYPE PLUMBING
J 0
(-4620 3982);
DISPLAY 0.340426 (-4620 3982);
PAINT GREEN (-4620 3982);
DISPLAY INVISIBLE (-4620 3982);
FORCEPROP 1 LAST VOLTAGE 0.0V
J 0
(-4620 3982);
DISPLAY 0.340426 (-4620 3982);
PAINT SKYBLUE (-4620 3982);
DISPLAY INVISIBLE (-4620 3982);
FORCEPROP 2 LAST CDS_LIB mstr_symbols
J 0
(-4575 4025);
PAINT ORANGE (-4575 4025);
DISPLAY INVISIBLE (-4575 4025);
FORCEPROP 1 LAST SIZE 1B
J 0
(-4500 3975);
DISPLAY 0.872340 (-4500 3975);
PAINT AQUA (-4500 3975);
DISPLAY INVISIBLE (-4500 3975);
FORCEPROP 1 LAST PATH I33
J 0
(-4500 4025);
DISPLAY 0.872340 (-4500 4025);
PAINT AQUA (-4500 4025);
DISPLAY INVISIBLE (-4500 4025);
FORCEPROP 1 LAST HDL_POWER GND
J 0
(-4575 4175);
DISPLAY 0.872340 (-4575 4175);
PAINT GREEN (-4575 4175);
DISPLAY INVISIBLE (-4575 4175);
FORCEADD CAP_A..1
(-4575 4225);
FORCEPROP 1 LASTPIN (-4575 4325) $PN 1
J 0
(-4565 4305);
DISPLAY 0.617021 (-4565 4305);
PAINT ORANGE (-4565 4305);
FORCEPROP 1 LASTPIN (-4575 4125) $PN 2
J 0
(-4565 4105);
DISPLAY 0.617021 (-4565 4105);
PAINT ORANGE (-4565 4105);
FORCEPROP 1 LAST MATERIAL X7R
J 0
(-4525 4125);
DISPLAY 0.617021 (-4525 4125);
PAINT SKYBLUE (-4525 4125);
FORCEPROP 1 LAST TOLERANCE 10%
J 0
(-4525 4175);
DISPLAY 0.617021 (-4525 4175);
PAINT SKYBLUE (-4525 4175);
FORCEPROP 1 LAST LOCATION C3F2
J 0
(-4525 4325);
DISPLAY 0.617021 (-4525 4325);
PAINT AQUA (-4525 4325);
FORCEPROP 1 LAST VOLTAGE 16V
J 0
(-4525 4225);
DISPLAY 0.617021 (-4525 4225);
PAINT SKYBLUE (-4525 4225);
FORCEPROP 1 LAST PACK_TYPE 0402V
J 0
(-4525 4025);
DISPLAY 0.617021 (-4525 4025);
PAINT SKYBLUE (-4525 4025);
FORCEPROP 1 LAST VALUE 0.1UF
J 0
(-4525 4275);
DISPLAY 0.617021 (-4525 4275);
PAINT SKYBLUE (-4525 4275);
FORCEPROP 1 LAST PART_NUMBER A36096-030
J 0
(-4525 4075);
DISPLAY 0.617021 (-4525 4075);
PAINT BLUE (-4525 4075);
FORCEPROP 2 LAST CDS_LOCATION C3F2
J 0
(-4525 4325);
DISPLAY 0.617021 (-4525 4325);
PAINT AQUA (-4525 4325);
DISPLAY INVISIBLE (-4525 4325);
FORCEPROP 2 LAST CDS_LIB dev_discrete
J 0
(-4575 4225);
PAINT ORANGE (-4575 4225);
DISPLAY INVISIBLE (-4575 4225);
FORCEPROP 1 LAST PATH I34
J 0
(-4525 4375);
DISPLAY 0.978723 (-4525 4375);
PAINT WHITE (-4525 4375);
DISPLAY INVISIBLE (-4525 4375);
FORCEPROP 0 LAST ROOM CLOCK_CPU1_OSC
J 0
(-4525 4425);
DISPLAY 1.021277 (-4525 4425);
PAINT ORANGE (-4525 4425);
DISPLAY INVISIBLE (-4525 4425);
FORCEPROP 2 LAST SEC_TYPE 0402V
J 0
(-4525 4425);
DISPLAY 1.021277 (-4525 4425);
PAINT ORANGE (-4525 4425);
DISPLAY INVISIBLE (-4525 4425);
FORCEPROP 2 LAST SEC 1
J 0
(-4525 4425);
DISPLAY 0.680851 (-4525 4425);
PAINT MONO (-4525 4425);
DISPLAY INVISIBLE (-4525 4425);
FORCEPROP 2 LAST CDS_SEC 1
J 0
(-4525 4375);
PAINT ORANGE (-4525 4375);
DISPLAY INVISIBLE (-4525 4375);
FORCEADD OFFPAGE..1
(-4850 3925);
FORCEPROP 2 LAST $XR0 104 
J 0
(-5102 3925);
DISPLAY 0.638298 (-5102 3925);
PAINT MONO (-5102 3925);
FORCEPROP 1 LAST COMMENT_BODY TRUE
J 0
(-4725 3825);
DISPLAY 0.872340 (-4725 3825);
PAINT GREEN (-4725 3825);
DISPLAY INVISIBLE (-4725 3825);
FORCEPROP 2 LAST PATH I36
J 0
(-4800 4000);
DISPLAY 1.021277 (-4800 4000);
PAINT ORANGE (-4800 4000);
DISPLAY INVISIBLE (-4800 4000);
FORCEPROP 2 LAST CDS_LIB mstr_standard
J 0
(-4850 3925);
PAINT ORANGE (-4850 3925);
DISPLAY INVISIBLE (-4850 3925);
FORCEPROP 1 LAST OFFPAGE TRUE
J 0
(-4525 3800);
DISPLAY 0.872340 (-4525 3800);
PAINT GREEN (-4525 3800);
DISPLAY INVISIBLE (-4525 3800);
FORCEADD RES..1
(525 4325);
FORCEPROP 1 LASTPIN (625 4325) $PN 2
J 0
(587 4337);
DISPLAY 0.617021 (587 4337);
PAINT ORANGE (587 4337);
FORCEPROP 1 LAST PART_NUMBER G21497-005
J 0
(650 4325);
DISPLAY 0.617021 (650 4325);
PAINT BLUE (650 4325);
FORCEPROP 1 LAST LOCATION R6F8
J 0
(475 4375);
DISPLAY 0.617021 (475 4375);
PAINT AQUA (475 4375);
FORCEPROP 1 LAST WATTAGE 1/16W
J 0
(350 4275);
DISPLAY 0.617021 (350 4275);
PAINT SKYBLUE (350 4275);
FORCEPROP 1 LAST VALUE 0.0
J 1
(300 4275);
DISPLAY 0.617021 (300 4275);
PAINT SKYBLUE (300 4275);
FORCEPROP 1 LASTPIN (425 4325) $PN 1
J 0
(437 4337);
DISPLAY 0.617021 (437 4337);
PAINT ORANGE (437 4337);
FORCEPROP 1 LAST TOLERANCE 5%
J 0
(500 4275);
DISPLAY 0.617021 (500 4275);
PAINT SKYBLUE (500 4275);
FORCEPROP 1 LAST PACK_TYPE 0402
J 0
(725 4275);
DISPLAY 0.617021 (725 4275);
PAINT SKYBLUE (725 4275);
FORCEPROP 1 LAST MATERIAL EMPTY
J 1
(650 4275);
DISPLAY 0.617021 (650 4275);
PAINT RED (650 4275);
FORCEPROP 2 LAST ROOM CLOCK_CPU0_OSC
J 0
(1000 4425);
DISPLAY 1.021277 (1000 4425);
PAINT ORANGE (1000 4425);
DISPLAY INVISIBLE (1000 4425);
FORCEPROP 2 LAST CDS_LIB mstr_discrete
J 0
(525 4325);
PAINT ORANGE (525 4325);
DISPLAY INVISIBLE (525 4325);
FORCEPROP 0 LAST NO_XNET_CONNECTION 1
J 0
(475 4525);
PAINT MONO (475 4525);
DISPLAY INVISIBLE (475 4525);
FORCEPROP 1 LAST PATH I37
J 0
(475 4475);
DISPLAY 0.978723 (475 4475);
PAINT WHITE (475 4475);
DISPLAY INVISIBLE (475 4475);
FORCEPROP 2 LAST SEC 1
J 0
(475 4525);
DISPLAY 0.680851 (475 4525);
PAINT MONO (475 4525);
DISPLAY INVISIBLE (475 4525);
FORCEPROP 2 LAST SEC_TYPE 0402
J 0
(475 4525);
DISPLAY 1.021277 (475 4525);
PAINT ORANGE (475 4525);
DISPLAY INVISIBLE (475 4525);
FORCEPROP 2 LAST CDS_LOCATION R6F8
J 0
(475 4375);
DISPLAY 0.617021 (475 4375);
PAINT AQUA (475 4375);
DISPLAY INVISIBLE (475 4375);
FORCEADD OFFPAGE..2
(1675 5175);
FORCEPROP 2 LAST $XR0 29 
J 0
(1864 5175);
DISPLAY 0.638298 (1864 5175);
PAINT MONO (1864 5175);
FORCEPROP 1 LAST COMMENT_BODY TRUE
J 0
(1630 5080);
DISPLAY 0.872340 (1630 5080);
PAINT GREEN (1630 5080);
DISPLAY INVISIBLE (1630 5080);
FORCEPROP 1 LAST OFFPAGE TRUE
J 0
(2000 5050);
DISPLAY 0.872340 (2000 5050);
PAINT GREEN (2000 5050);
DISPLAY INVISIBLE (2000 5050);
FORCEPROP 2 LAST CDS_LIB mstr_standard
J 0
(1675 5175);
PAINT ORANGE (1675 5175);
DISPLAY INVISIBLE (1675 5175);
FORCEPROP 2 LAST PATH I38
J 0
(1850 5250);
DISPLAY 1.021277 (1850 5250);
PAINT ORANGE (1850 5250);
DISPLAY INVISIBLE (1850 5250);
FORCEADD RES..1
(525 5025);
FORCEPROP 1 LAST WATTAGE 1/16W
J 0
(350 4975);
DISPLAY 0.617021 (350 4975);
PAINT SKYBLUE (350 4975);
FORCEPROP 1 LASTPIN (625 5025) $PN 2
J 0
(587 5037);
DISPLAY 0.617021 (587 5037);
PAINT ORANGE (587 5037);
FORCEPROP 1 LAST PART_NUMBER G21497-005
J 0
(675 5025);
DISPLAY 0.617021 (675 5025);
PAINT BLUE (675 5025);
FORCEPROP 1 LAST PACK_TYPE 0402
J 0
(725 4975);
DISPLAY 0.617021 (725 4975);
PAINT SKYBLUE (725 4975);
FORCEPROP 1 LAST LOCATION R6F6
J 0
(475 5075);
DISPLAY 0.617021 (475 5075);
PAINT AQUA (475 5075);
FORCEPROP 1 LAST MATERIAL EMPTY
J 1
(650 4975);
DISPLAY 0.617021 (650 4975);
PAINT RED (650 4975);
FORCEPROP 1 LAST TOLERANCE 5%
J 0
(500 4975);
DISPLAY 0.617021 (500 4975);
PAINT SKYBLUE (500 4975);
FORCEPROP 1 LASTPIN (425 5025) $PN 1
J 0
(437 5037);
DISPLAY 0.617021 (437 5037);
PAINT ORANGE (437 5037);
FORCEPROP 1 LAST VALUE 0.0
J 1
(300 4975);
DISPLAY 0.617021 (300 4975);
PAINT SKYBLUE (300 4975);
FORCEPROP 2 LAST SEC_TYPE 0402
J 0
(475 5225);
DISPLAY 1.021277 (475 5225);
PAINT ORANGE (475 5225);
DISPLAY INVISIBLE (475 5225);
FORCEPROP 2 LAST SEC 1
J 0
(475 5225);
DISPLAY 0.680851 (475 5225);
PAINT MONO (475 5225);
DISPLAY INVISIBLE (475 5225);
FORCEPROP 0 LAST NO_XNET_CONNECTION 1
J 0
(475 5225);
PAINT MONO (475 5225);
DISPLAY INVISIBLE (475 5225);
FORCEPROP 1 LAST PATH I41
J 0
(475 5175);
DISPLAY 0.978723 (475 5175);
PAINT WHITE (475 5175);
DISPLAY INVISIBLE (475 5175);
FORCEPROP 2 LAST ROOM CLOCK_CPU0_OSC
J 0
(1000 5125);
DISPLAY 1.021277 (1000 5125);
PAINT ORANGE (1000 5125);
DISPLAY INVISIBLE (1000 5125);
FORCEPROP 2 LAST CDS_LIB mstr_discrete
J 0
(525 5025);
PAINT ORANGE (525 5025);
DISPLAY INVISIBLE (525 5025);
FORCEPROP 2 LAST CDS_LOCATION R6F6
J 0
(475 5075);
DISPLAY 0.617021 (475 5075);
PAINT AQUA (475 5075);
DISPLAY INVISIBLE (475 5075);
FORCEADD OFFPAGE..1
(-550 5175);
FORCEPROP 2 LAST $XR0 104 
J 0
(-802 5175);
DISPLAY 0.638298 (-802 5175);
PAINT MONO (-802 5175);
FORCEPROP 1 LAST OFFPAGE TRUE
J 0
(-225 5050);
DISPLAY 0.872340 (-225 5050);
PAINT GREEN (-225 5050);
DISPLAY INVISIBLE (-225 5050);
FORCEPROP 1 LAST COMMENT_BODY TRUE
J 0
(-425 5075);
DISPLAY 0.872340 (-425 5075);
PAINT GREEN (-425 5075);
DISPLAY INVISIBLE (-425 5075);
FORCEPROP 2 LAST CDS_LIB mstr_standard
J 0
(-550 5175);
PAINT ORANGE (-550 5175);
DISPLAY INVISIBLE (-550 5175);
FORCEPROP 2 LAST PATH I42
J 0
(-500 5250);
DISPLAY 1.021277 (-500 5250);
PAINT ORANGE (-500 5250);
DISPLAY INVISIBLE (-500 5250);
FORCEADD OFFPAGE..2
(1675 4475);
FORCEPROP 2 LAST $XR0 29 
J 0
(1864 4475);
DISPLAY 0.638298 (1864 4475);
PAINT MONO (1864 4475);
FORCEPROP 2 LAST PATH I44
J 0
(1850 4550);
DISPLAY 1.021277 (1850 4550);
PAINT ORANGE (1850 4550);
DISPLAY INVISIBLE (1850 4550);
FORCEPROP 1 LAST OFFPAGE TRUE
J 0
(2000 4350);
DISPLAY 0.872340 (2000 4350);
PAINT GREEN (2000 4350);
DISPLAY INVISIBLE (2000 4350);
FORCEPROP 2 LAST CDS_LIB mstr_standard
J 0
(1675 4475);
PAINT ORANGE (1675 4475);
DISPLAY INVISIBLE (1675 4475);
FORCEPROP 1 LAST COMMENT_BODY TRUE
J 0
(1630 4380);
DISPLAY 0.872340 (1630 4380);
PAINT GREEN (1630 4380);
DISPLAY INVISIBLE (1630 4380);
FORCEADD OFFPAGE..2
(1675 3775);
FORCEPROP 2 LAST $XR0 63 
J 0
(1864 3775);
DISPLAY 0.638298 (1864 3775);
PAINT MONO (1864 3775);
FORCEPROP 1 LAST COMMENT_BODY TRUE
J 0
(1630 3680);
DISPLAY 0.872340 (1630 3680);
PAINT GREEN (1630 3680);
DISPLAY INVISIBLE (1630 3680);
FORCEPROP 2 LAST CDS_LIB mstr_standard
J 0
(1675 3775);
PAINT ORANGE (1675 3775);
DISPLAY INVISIBLE (1675 3775);
FORCEPROP 2 LAST PATH I46
J 0
(1850 3850);
DISPLAY 1.021277 (1850 3850);
PAINT ORANGE (1850 3850);
DISPLAY INVISIBLE (1850 3850);
FORCEPROP 1 LAST OFFPAGE TRUE
J 0
(2000 3650);
DISPLAY 0.872340 (2000 3650);
PAINT GREEN (2000 3650);
DISPLAY INVISIBLE (2000 3650);
FORCEADD OFFPAGE..2
(1675 3075);
FORCEPROP 2 LAST $XR0 63 
J 0
(1864 3075);
DISPLAY 0.638298 (1864 3075);
PAINT MONO (1864 3075);
FORCEPROP 1 LAST COMMENT_BODY TRUE
J 0
(1630 2980);
DISPLAY 0.872340 (1630 2980);
PAINT GREEN (1630 2980);
DISPLAY INVISIBLE (1630 2980);
FORCEPROP 1 LAST OFFPAGE TRUE
J 0
(2000 2950);
DISPLAY 0.872340 (2000 2950);
PAINT GREEN (2000 2950);
DISPLAY INVISIBLE (2000 2950);
FORCEPROP 2 LAST CDS_LIB mstr_standard
J 0
(1675 3075);
PAINT ORANGE (1675 3075);
DISPLAY INVISIBLE (1675 3075);
FORCEPROP 2 LAST PATH I48
J 0
(1850 3150);
DISPLAY 1.021277 (1850 3150);
PAINT ORANGE (1850 3150);
DISPLAY INVISIBLE (1850 3150);
FORCEADD RES..1
(525 3625);
FORCEPROP 1 LAST PART_NUMBER G21497-005
J 0
(650 3625);
DISPLAY 0.617021 (650 3625);
PAINT BLUE (650 3625);
FORCEPROP 1 LAST LOCATION R3F1
J 0
(475 3675);
DISPLAY 0.617021 (475 3675);
PAINT AQUA (475 3675);
FORCEPROP 1 LAST MATERIAL EMPTY
J 1
(650 3575);
DISPLAY 0.617021 (650 3575);
PAINT RED (650 3575);
FORCEPROP 1 LAST WATTAGE 1/16W
J 0
(350 3575);
DISPLAY 0.617021 (350 3575);
PAINT SKYBLUE (350 3575);
FORCEPROP 1 LASTPIN (425 3625) $PN 1
J 0
(437 3637);
DISPLAY 0.617021 (437 3637);
PAINT ORANGE (437 3637);
FORCEPROP 1 LASTPIN (625 3625) $PN 2
J 0
(587 3637);
DISPLAY 0.617021 (587 3637);
PAINT ORANGE (587 3637);
FORCEPROP 1 LAST TOLERANCE 5%
J 0
(500 3575);
DISPLAY 0.617021 (500 3575);
PAINT SKYBLUE (500 3575);
FORCEPROP 1 LAST VALUE 0.0
J 1
(300 3575);
DISPLAY 0.617021 (300 3575);
PAINT SKYBLUE (300 3575);
FORCEPROP 1 LAST PACK_TYPE 0402
J 1
(775 3575);
DISPLAY 0.617021 (775 3575);
PAINT SKYBLUE (775 3575);
FORCEPROP 2 LAST ROOM CLOCK_CPU1_OSC
J 0
(1000 3725);
DISPLAY 1.021277 (1000 3725);
PAINT ORANGE (1000 3725);
DISPLAY INVISIBLE (1000 3725);
FORCEPROP 2 LAST CDS_LIB mstr_discrete
J 0
(525 3625);
PAINT ORANGE (525 3625);
DISPLAY INVISIBLE (525 3625);
FORCEPROP 2 LAST SEC_TYPE 0402
J 0
(475 3825);
DISPLAY 1.021277 (475 3825);
PAINT ORANGE (475 3825);
DISPLAY INVISIBLE (475 3825);
FORCEPROP 0 LAST NO_XNET_CONNECTION 1
J 0
(475 3825);
PAINT MONO (475 3825);
DISPLAY INVISIBLE (475 3825);
FORCEPROP 2 LAST SEC 1
J 0
(475 3825);
DISPLAY 0.680851 (475 3825);
PAINT MONO (475 3825);
DISPLAY INVISIBLE (475 3825);
FORCEPROP 1 LAST PATH I51
J 0
(475 3775);
DISPLAY 0.978723 (475 3775);
PAINT WHITE (475 3775);
DISPLAY INVISIBLE (475 3775);
FORCEPROP 2 LAST CDS_LOCATION R3F1
J 0
(475 3675);
DISPLAY 0.617021 (475 3675);
PAINT AQUA (475 3675);
DISPLAY INVISIBLE (475 3675);
FORCEADD RES..1
(525 2925);
FORCEPROP 1 LAST PART_NUMBER G21497-005
J 0
(650 2925);
DISPLAY 0.617021 (650 2925);
PAINT BLUE (650 2925);
FORCEPROP 1 LAST PACK_TYPE 0402
J 1
(775 2875);
DISPLAY 0.617021 (775 2875);
PAINT SKYBLUE (775 2875);
FORCEPROP 1 LAST WATTAGE 1/16W
J 0
(350 2875);
DISPLAY 0.617021 (350 2875);
PAINT SKYBLUE (350 2875);
FORCEPROP 1 LAST MATERIAL EMPTY
J 1
(650 2875);
DISPLAY 0.617021 (650 2875);
PAINT RED (650 2875);
FORCEPROP 1 LAST TOLERANCE 5%
J 0
(500 2875);
DISPLAY 0.617021 (500 2875);
PAINT SKYBLUE (500 2875);
FORCEPROP 1 LASTPIN (625 2925) $PN 2
J 0
(587 2937);
DISPLAY 0.617021 (587 2937);
PAINT ORANGE (587 2937);
FORCEPROP 1 LAST LOCATION R3F3
J 0
(475 2975);
DISPLAY 0.617021 (475 2975);
PAINT AQUA (475 2975);
FORCEPROP 1 LASTPIN (425 2925) $PN 1
J 0
(437 2937);
DISPLAY 0.617021 (437 2937);
PAINT ORANGE (437 2937);
FORCEPROP 1 LAST VALUE 0.0
J 1
(300 2875);
DISPLAY 0.617021 (300 2875);
PAINT SKYBLUE (300 2875);
FORCEPROP 2 LAST SEC_TYPE 0402
J 0
(475 3125);
DISPLAY 1.021277 (475 3125);
PAINT ORANGE (475 3125);
DISPLAY INVISIBLE (475 3125);
FORCEPROP 2 LAST SEC 1
J 0
(475 3125);
DISPLAY 0.680851 (475 3125);
PAINT MONO (475 3125);
DISPLAY INVISIBLE (475 3125);
FORCEPROP 0 LAST NO_XNET_CONNECTION 1
J 0
(475 3125);
PAINT MONO (475 3125);
DISPLAY INVISIBLE (475 3125);
FORCEPROP 2 LAST ROOM CLOCK_CPU1_OSC
J 0
(1000 3025);
DISPLAY 1.021277 (1000 3025);
PAINT ORANGE (1000 3025);
DISPLAY INVISIBLE (1000 3025);
FORCEPROP 2 LAST CDS_LIB mstr_discrete
J 0
(525 2925);
PAINT ORANGE (525 2925);
DISPLAY INVISIBLE (525 2925);
FORCEPROP 1 LAST PATH I53
J 0
(475 3075);
DISPLAY 0.978723 (475 3075);
PAINT WHITE (475 3075);
DISPLAY INVISIBLE (475 3075);
FORCEPROP 2 LAST CDS_LOCATION R3F3
J 0
(475 2975);
DISPLAY 0.617021 (475 2975);
PAINT AQUA (475 2975);
DISPLAY INVISIBLE (475 2975);
FORCEADD OFFPAGE..1
(-550 4475);
FORCEPROP 2 LAST $XR0 104 
J 0
(-802 4475);
DISPLAY 0.638298 (-802 4475);
PAINT MONO (-802 4475);
FORCEPROP 2 LAST PATH I54
J 0
(-500 4550);
DISPLAY 1.021277 (-500 4550);
PAINT ORANGE (-500 4550);
DISPLAY INVISIBLE (-500 4550);
FORCEPROP 1 LAST COMMENT_BODY TRUE
J 0
(-425 4375);
DISPLAY 0.872340 (-425 4375);
PAINT GREEN (-425 4375);
DISPLAY INVISIBLE (-425 4375);
FORCEPROP 1 LAST OFFPAGE TRUE
J 0
(-225 4350);
DISPLAY 0.872340 (-225 4350);
PAINT GREEN (-225 4350);
DISPLAY INVISIBLE (-225 4350);
FORCEPROP 2 LAST CDS_LIB mstr_standard
J 0
(-550 4475);
PAINT ORANGE (-550 4475);
DISPLAY INVISIBLE (-550 4475);
FORCEADD OFFPAGE..1
(-550 3775);
FORCEPROP 2 LAST $XR0 104 
J 0
(-802 3775);
DISPLAY 0.638298 (-802 3775);
PAINT MONO (-802 3775);
FORCEPROP 2 LAST CDS_LIB mstr_standard
J 0
(-550 3775);
PAINT ORANGE (-550 3775);
DISPLAY INVISIBLE (-550 3775);
FORCEPROP 2 LAST PATH I55
J 0
(-500 3850);
DISPLAY 1.021277 (-500 3850);
PAINT ORANGE (-500 3850);
DISPLAY INVISIBLE (-500 3850);
FORCEPROP 1 LAST COMMENT_BODY TRUE
J 0
(-425 3675);
DISPLAY 0.872340 (-425 3675);
PAINT GREEN (-425 3675);
DISPLAY INVISIBLE (-425 3675);
FORCEPROP 1 LAST OFFPAGE TRUE
J 0
(-225 3650);
DISPLAY 0.872340 (-225 3650);
PAINT GREEN (-225 3650);
DISPLAY INVISIBLE (-225 3650);
FORCEADD OFFPAGE..1
(-550 3075);
FORCEPROP 2 LAST $XR0 104 
J 0
(-802 3075);
DISPLAY 0.638298 (-802 3075);
PAINT MONO (-802 3075);
FORCEPROP 1 LAST COMMENT_BODY TRUE
J 0
(-425 2975);
DISPLAY 0.872340 (-425 2975);
PAINT GREEN (-425 2975);
DISPLAY INVISIBLE (-425 2975);
FORCEPROP 1 LAST OFFPAGE TRUE
J 0
(-225 2950);
DISPLAY 0.872340 (-225 2950);
PAINT GREEN (-225 2950);
DISPLAY INVISIBLE (-225 2950);
FORCEPROP 2 LAST CDS_LIB mstr_standard
J 0
(-550 3075);
PAINT ORANGE (-550 3075);
DISPLAY INVISIBLE (-550 3075);
FORCEPROP 2 LAST PATH I56
J 0
(-500 3150);
DISPLAY 1.021277 (-500 3150);
PAINT ORANGE (-500 3150);
DISPLAY INVISIBLE (-500 3150);
FORCEADD OFFPAGE..2
(-2150 4875);
FORCEPROP 2 LAST $XR0 104 
J 0
(-1961 4875);
DISPLAY 0.638298 (-1961 4875);
PAINT MONO (-1961 4875);
FORCEPROP 1 LAST COMMENT_BODY TRUE
J 0
(-2195 4780);
DISPLAY 0.872340 (-2195 4780);
PAINT GREEN (-2195 4780);
DISPLAY INVISIBLE (-2195 4780);
FORCEPROP 2 LAST CDS_LIB mstr_standard
J 0
(-2150 4875);
PAINT ORANGE (-2150 4875);
DISPLAY INVISIBLE (-2150 4875);
FORCEPROP 1 LAST OFFPAGE TRUE
J 0
(-1825 4750);
DISPLAY 0.872340 (-1825 4750);
PAINT GREEN (-1825 4750);
DISPLAY INVISIBLE (-1825 4750);
FORCEPROP 2 LAST PATH I57
J 0
(-1975 4950);
DISPLAY 1.021277 (-1975 4950);
PAINT ORANGE (-1975 4950);
DISPLAY INVISIBLE (-1975 4950);
FORCEADD OFFPAGE..2
(-2150 4775);
FORCEPROP 2 LAST $XR0 104 
J 0
(-1961 4775);
DISPLAY 0.638298 (-1961 4775);
PAINT MONO (-1961 4775);
FORCEPROP 2 LAST CDS_LIB mstr_standard
J 0
(-2150 4775);
PAINT ORANGE (-2150 4775);
DISPLAY INVISIBLE (-2150 4775);
FORCEPROP 1 LAST COMMENT_BODY TRUE
J 0
(-2195 4680);
DISPLAY 0.872340 (-2195 4680);
PAINT GREEN (-2195 4680);
DISPLAY INVISIBLE (-2195 4680);
FORCEPROP 1 LAST OFFPAGE TRUE
J 0
(-1825 4650);
DISPLAY 0.872340 (-1825 4650);
PAINT GREEN (-1825 4650);
DISPLAY INVISIBLE (-1825 4650);
FORCEPROP 2 LAST PATH I58
J 0
(-1975 4850);
DISPLAY 1.021277 (-1975 4850);
PAINT ORANGE (-1975 4850);
DISPLAY INVISIBLE (-1975 4850);
FORCEADD OFFPAGE..2
(-2450 4025);
FORCEPROP 2 LAST $XR0 104 
J 0
(-2261 4025);
DISPLAY 0.638298 (-2261 4025);
PAINT MONO (-2261 4025);
FORCEPROP 1 LAST COMMENT_BODY TRUE
J 0
(-2495 3930);
DISPLAY 0.872340 (-2495 3930);
PAINT GREEN (-2495 3930);
DISPLAY INVISIBLE (-2495 3930);
FORCEPROP 2 LAST CDS_LIB mstr_standard
J 0
(-2450 4025);
PAINT ORANGE (-2450 4025);
DISPLAY INVISIBLE (-2450 4025);
FORCEPROP 1 LAST OFFPAGE TRUE
J 0
(-2125 3900);
DISPLAY 0.872340 (-2125 3900);
PAINT GREEN (-2125 3900);
DISPLAY INVISIBLE (-2125 3900);
FORCEPROP 2 LAST PATH I59
J 0
(-2275 4100);
DISPLAY 1.021277 (-2275 4100);
PAINT ORANGE (-2275 4100);
DISPLAY INVISIBLE (-2275 4100);
FORCEADD OFFPAGE..2
(-2450 3925);
FORCEPROP 2 LAST $XR0 104 
J 0
(-2261 3925);
DISPLAY 0.638298 (-2261 3925);
PAINT MONO (-2261 3925);
FORCEPROP 1 LAST COMMENT_BODY TRUE
J 0
(-2495 3830);
DISPLAY 0.872340 (-2495 3830);
PAINT GREEN (-2495 3830);
DISPLAY INVISIBLE (-2495 3830);
FORCEPROP 2 LAST CDS_LIB mstr_standard
J 0
(-2450 3925);
PAINT ORANGE (-2450 3925);
DISPLAY INVISIBLE (-2450 3925);
FORCEPROP 1 LAST OFFPAGE TRUE
J 0
(-2125 3800);
DISPLAY 0.872340 (-2125 3800);
PAINT GREEN (-2125 3800);
DISPLAY INVISIBLE (-2125 3800);
FORCEPROP 2 LAST PATH I60
J 0
(-2275 4000);
DISPLAY 1.021277 (-2275 4000);
PAINT ORANGE (-2275 4000);
DISPLAY INVISIBLE (-2275 4000);
FORCEADD RES..1
(525 5175);
FORCEPROP 1 LAST MATERIAL CHIP
J 1
(650 5125);
DISPLAY 0.617021 (650 5125);
PAINT SKYBLUE (650 5125);
FORCEPROP 1 LAST PACK_TYPE 0402
J 0
(725 5125);
DISPLAY 0.617021 (725 5125);
PAINT SKYBLUE (725 5125);
FORCEPROP 1 LAST PART_NUMBER G21497-005
J 0
(650 5175);
DISPLAY 0.617021 (650 5175);
PAINT BLUE (650 5175);
FORCEPROP 1 LAST TOLERANCE 5%
J 0
(500 5125);
DISPLAY 0.617021 (500 5125);
PAINT SKYBLUE (500 5125);
FORCEPROP 1 LAST VALUE 0.0
J 1
(300 5125);
DISPLAY 0.617021 (300 5125);
PAINT SKYBLUE (300 5125);
FORCEPROP 1 LASTPIN (425 5175) $PN 1
J 0
(437 5187);
DISPLAY 0.617021 (437 5187);
PAINT ORANGE (437 5187);
FORCEPROP 1 LASTPIN (625 5175) $PN 2
J 0
(587 5187);
DISPLAY 0.617021 (587 5187);
PAINT ORANGE (587 5187);
FORCEPROP 1 LAST WATTAGE 1/16W
J 0
(350 5125);
DISPLAY 0.617021 (350 5125);
PAINT SKYBLUE (350 5125);
FORCEPROP 1 LAST LOCATION R6F7
J 0
(475 5225);
DISPLAY 0.617021 (475 5225);
PAINT AQUA (475 5225);
FORCEPROP 1 LAST PATH I67
J 0
(475 5325);
DISPLAY 0.978723 (475 5325);
PAINT WHITE (475 5325);
DISPLAY INVISIBLE (475 5325);
FORCEPROP 0 LAST NO_XNET_CONNECTION 1
J 0
(475 5375);
PAINT MONO (475 5375);
DISPLAY INVISIBLE (475 5375);
FORCEPROP 0 LAST ROOM CLOCK_CPU0_OSC
J 0
(475 5325);
DISPLAY 1.021277 (475 5325);
PAINT ORANGE (475 5325);
DISPLAY INVISIBLE (475 5325);
FORCEPROP 2 LAST CDS_LOCATION R6F7
J 0
(475 5225);
DISPLAY 0.617021 (475 5225);
PAINT AQUA (475 5225);
DISPLAY INVISIBLE (475 5225);
FORCEPROP 2 LAST SEC 1
J 0
(475 5375);
DISPLAY 0.680851 (475 5375);
PAINT MONO (475 5375);
DISPLAY INVISIBLE (475 5375);
FORCEPROP 2 LAST SEC_TYPE 0402
J 0
(475 5375);
DISPLAY 1.021277 (475 5375);
PAINT ORANGE (475 5375);
DISPLAY INVISIBLE (475 5375);
FORCEPROP 2 LAST CDS_LIB mstr_discrete
J 0
(525 5175);
PAINT ORANGE (525 5175);
DISPLAY INVISIBLE (525 5175);
FORCEADD RES..1
(525 4475);
FORCEPROP 1 LAST PART_NUMBER G21497-005
J 0
(650 4475);
DISPLAY 0.617021 (650 4475);
PAINT BLUE (650 4475);
FORCEPROP 1 LAST WATTAGE 1/16W
J 0
(350 4425);
DISPLAY 0.617021 (350 4425);
PAINT SKYBLUE (350 4425);
FORCEPROP 1 LAST VALUE 0.0
J 1
(300 4425);
DISPLAY 0.617021 (300 4425);
PAINT SKYBLUE (300 4425);
FORCEPROP 1 LASTPIN (625 4475) $PN 2
J 0
(587 4487);
DISPLAY 0.617021 (587 4487);
PAINT ORANGE (587 4487);
FORCEPROP 1 LAST LOCATION R6F9
J 0
(475 4525);
DISPLAY 0.617021 (475 4525);
PAINT AQUA (475 4525);
FORCEPROP 1 LAST PACK_TYPE 0402
J 0
(725 4425);
DISPLAY 0.617021 (725 4425);
PAINT SKYBLUE (725 4425);
FORCEPROP 1 LAST TOLERANCE 5%
J 0
(500 4425);
DISPLAY 0.617021 (500 4425);
PAINT SKYBLUE (500 4425);
FORCEPROP 1 LASTPIN (425 4475) $PN 1
J 0
(437 4487);
DISPLAY 0.617021 (437 4487);
PAINT ORANGE (437 4487);
FORCEPROP 1 LAST MATERIAL CHIP
J 1
(650 4425);
DISPLAY 0.617021 (650 4425);
PAINT SKYBLUE (650 4425);
FORCEPROP 2 LAST CDS_LIB mstr_discrete
J 0
(525 4475);
PAINT ORANGE (525 4475);
DISPLAY INVISIBLE (525 4475);
FORCEPROP 2 LAST SEC_TYPE 0402
J 0
(475 4675);
DISPLAY 1.021277 (475 4675);
PAINT ORANGE (475 4675);
DISPLAY INVISIBLE (475 4675);
FORCEPROP 0 LAST NO_XNET_CONNECTION 1
J 0
(475 4675);
PAINT MONO (475 4675);
DISPLAY INVISIBLE (475 4675);
FORCEPROP 2 LAST SEC 1
J 0
(475 4675);
DISPLAY 0.680851 (475 4675);
PAINT MONO (475 4675);
DISPLAY INVISIBLE (475 4675);
FORCEPROP 1 LAST PATH I68
J 0
(475 4625);
DISPLAY 0.978723 (475 4625);
PAINT WHITE (475 4625);
DISPLAY INVISIBLE (475 4625);
FORCEPROP 0 LAST ROOM CLOCK_CPU0_OSC
J 0
(475 4625);
DISPLAY 1.021277 (475 4625);
PAINT ORANGE (475 4625);
DISPLAY INVISIBLE (475 4625);
FORCEPROP 2 LAST CDS_LOCATION R6F9
J 0
(475 4525);
DISPLAY 0.617021 (475 4525);
PAINT AQUA (475 4525);
DISPLAY INVISIBLE (475 4525);
FORCEADD RES..1
(525 3775);
FORCEPROP 1 LAST PACK_TYPE 0402
J 1
(775 3725);
DISPLAY 0.617021 (775 3725);
PAINT SKYBLUE (775 3725);
FORCEPROP 1 LAST PART_NUMBER G21497-005
J 0
(650 3775);
DISPLAY 0.617021 (650 3775);
PAINT BLUE (650 3775);
FORCEPROP 1 LAST LOCATION R3F2
J 0
(475 3825);
DISPLAY 0.617021 (475 3825);
PAINT AQUA (475 3825);
FORCEPROP 1 LAST VALUE 0.0
J 1
(300 3725);
DISPLAY 0.617021 (300 3725);
PAINT SKYBLUE (300 3725);
FORCEPROP 1 LAST WATTAGE 1/16W
J 0
(350 3725);
DISPLAY 0.617021 (350 3725);
PAINT SKYBLUE (350 3725);
FORCEPROP 1 LASTPIN (425 3775) $PN 1
J 0
(437 3787);
DISPLAY 0.617021 (437 3787);
PAINT ORANGE (437 3787);
FORCEPROP 1 LASTPIN (625 3775) $PN 2
J 0
(587 3787);
DISPLAY 0.617021 (587 3787);
PAINT ORANGE (587 3787);
FORCEPROP 1 LAST MATERIAL CHIP
J 1
(650 3725);
DISPLAY 0.617021 (650 3725);
PAINT SKYBLUE (650 3725);
FORCEPROP 1 LAST TOLERANCE 5%
J 0
(500 3725);
DISPLAY 0.617021 (500 3725);
PAINT SKYBLUE (500 3725);
FORCEPROP 2 LAST CDS_LOCATION R3F2
J 0
(475 3825);
DISPLAY 0.617021 (475 3825);
PAINT AQUA (475 3825);
DISPLAY INVISIBLE (475 3825);
FORCEPROP 0 LAST NO_XNET_CONNECTION 1
J 0
(475 3975);
PAINT MONO (475 3975);
DISPLAY INVISIBLE (475 3975);
FORCEPROP 0 LAST ROOM CLOCK_CPU1_OSC
J 0
(475 3925);
DISPLAY 1.021277 (475 3925);
PAINT ORANGE (475 3925);
DISPLAY INVISIBLE (475 3925);
FORCEPROP 1 LAST PATH I69
J 0
(475 3925);
DISPLAY 0.978723 (475 3925);
PAINT WHITE (475 3925);
DISPLAY INVISIBLE (475 3925);
FORCEPROP 2 LAST SEC 1
J 0
(475 3975);
DISPLAY 0.680851 (475 3975);
PAINT MONO (475 3975);
DISPLAY INVISIBLE (475 3975);
FORCEPROP 2 LAST SEC_TYPE 0402
J 0
(475 3975);
DISPLAY 1.021277 (475 3975);
PAINT ORANGE (475 3975);
DISPLAY INVISIBLE (475 3975);
FORCEPROP 2 LAST CDS_LIB mstr_discrete
J 0
(525 3775);
PAINT ORANGE (525 3775);
DISPLAY INVISIBLE (525 3775);
FORCEADD RES..1
(525 3075);
FORCEPROP 1 LAST VALUE 0.0
J 1
(300 3025);
DISPLAY 0.617021 (300 3025);
PAINT SKYBLUE (300 3025);
FORCEPROP 1 LASTPIN (625 3075) $PN 2
J 0
(587 3087);
DISPLAY 0.617021 (587 3087);
PAINT ORANGE (587 3087);
FORCEPROP 1 LAST TOLERANCE 5%
J 0
(500 3025);
DISPLAY 0.617021 (500 3025);
PAINT SKYBLUE (500 3025);
FORCEPROP 1 LAST MATERIAL CHIP
J 1
(650 3025);
DISPLAY 0.617021 (650 3025);
PAINT SKYBLUE (650 3025);
FORCEPROP 1 LAST LOCATION R3F4
J 0
(475 3125);
DISPLAY 0.617021 (475 3125);
PAINT AQUA (475 3125);
FORCEPROP 1 LASTPIN (425 3075) $PN 1
J 0
(437 3087);
DISPLAY 0.617021 (437 3087);
PAINT ORANGE (437 3087);
FORCEPROP 1 LAST PACK_TYPE 0402
J 1
(775 3025);
DISPLAY 0.617021 (775 3025);
PAINT SKYBLUE (775 3025);
FORCEPROP 1 LAST WATTAGE 1/16W
J 0
(350 3025);
DISPLAY 0.617021 (350 3025);
PAINT SKYBLUE (350 3025);
FORCEPROP 1 LAST PART_NUMBER G21497-005
J 0
(650 3075);
DISPLAY 0.617021 (650 3075);
PAINT BLUE (650 3075);
FORCEPROP 2 LAST CDS_LIB mstr_discrete
J 0
(525 3075);
PAINT ORANGE (525 3075);
DISPLAY INVISIBLE (525 3075);
FORCEPROP 2 LAST SEC_TYPE 0402
J 0
(475 3275);
DISPLAY 1.021277 (475 3275);
PAINT ORANGE (475 3275);
DISPLAY INVISIBLE (475 3275);
FORCEPROP 2 LAST SEC 1
J 0
(475 3275);
DISPLAY 0.680851 (475 3275);
PAINT MONO (475 3275);
DISPLAY INVISIBLE (475 3275);
FORCEPROP 0 LAST ROOM CLOCK_CPU1_OSC
J 0
(475 3225);
DISPLAY 1.021277 (475 3225);
PAINT ORANGE (475 3225);
DISPLAY INVISIBLE (475 3225);
FORCEPROP 0 LAST NO_XNET_CONNECTION 1
J 0
(475 3275);
PAINT MONO (475 3275);
DISPLAY INVISIBLE (475 3275);
FORCEPROP 2 LAST CDS_LOCATION R3F4
J 0
(475 3125);
DISPLAY 0.617021 (475 3125);
PAINT AQUA (475 3125);
DISPLAY INVISIBLE (475 3125);
FORCEPROP 1 LAST PATH I70
J 0
(475 3225);
DISPLAY 0.978723 (475 3225);
PAINT WHITE (475 3225);
DISPLAY INVISIBLE (475 3225);
FORCEADD OSC_C..17
(-3400 4775);
FORCEPROP 1 LAST VALUE 156.25MHZ
J 0
(-3850 5000);
DISPLAY 0.617021 (-3850 5000);
PAINT SKYBLUE (-3850 5000);
FORCEPROP 1 LAST MATERIAL OSC
J 0
(-3850 5050);
DISPLAY 0.617021 (-3850 5050);
PAINT SKYBLUE (-3850 5050);
FORCEPROP 2 LASTPIN (-2900 4875) $PN 5
J 0
(-2890 4885);
DISPLAY 0.617021 (-2890 4885);
PAINT ORANGE (-2890 4885);
FORCEPROP 2 LASTPIN (-2900 4675) $PN 3
J 0
(-2890 4685);
DISPLAY 0.617021 (-2890 4685);
PAINT ORANGE (-2890 4685);
FORCEPROP 2 LASTPIN (-2900 4775) $PN 4
J 0
(-2890 4785);
DISPLAY 0.617021 (-2890 4785);
PAINT ORANGE (-2890 4785);
FORCEPROP 2 LASTPIN (-3900 4875) $PN 6
J 2
(-3910 4885);
DISPLAY 0.617021 (-3910 4885);
PAINT ORANGE (-3910 4885);
FORCEPROP 2 LASTPIN (-3900 4775) $PN 1
J 2
(-3910 4785);
DISPLAY 0.617021 (-3910 4785);
PAINT ORANGE (-3910 4785);
FORCEPROP 2 LASTPIN (-3900 4675) $PN 2
J 2
(-3910 4685);
DISPLAY 0.617021 (-3910 4685);
PAINT ORANGE (-3910 4685);
FORCEPROP 1 LAST LOCATION Y6F1
J 0
(-3850 5100);
DISPLAY 0.617021 (-3850 5100);
PAINT AQUA (-3850 5100);
FORCEPROP 1 LAST PART_NUMBER G63831-004
J 0
(-3850 4525);
DISPLAY 0.617021 (-3850 4525);
PAINT BLUE (-3850 4525);
FORCEPROP 1 LAST CDS_LMAN_SYM_OUTLINE -450,200,450,-200
J 0
(-3400 4775);
DISPLAY 0.468085 (-3400 4775);
PAINT GREEN (-3400 4775);
DISPLAY INVISIBLE (-3400 4775);
FORCEPROP 2 LAST CDS_LIB mstr_discrete
J 0
(-3400 4775);
PAINT ORANGE (-3400 4775);
DISPLAY INVISIBLE (-3400 4775);
FORCEPROP 1 LAST PATH I71
J 0
(-3355 5005);
PAINT GREEN (-3355 5005);
DISPLAY INVISIBLE (-3355 5005);
FORCEPROP 2 LAST CDS_LOCATION Y6F1
J 0
(-3850 5100);
DISPLAY 0.617021 (-3850 5100);
PAINT AQUA (-3850 5100);
DISPLAY INVISIBLE (-3850 5100);
FORCEPROP 2 LAST SEC_TYPE 6P10
J 0
(-3850 5150);
DISPLAY 1.021277 (-3850 5150);
PAINT ORANGE (-3850 5150);
DISPLAY INVISIBLE (-3850 5150);
FORCEPROP 2 LAST SEC 1
J 0
(-3850 5150);
DISPLAY 0.680851 (-3850 5150);
PAINT MONO (-3850 5150);
DISPLAY INVISIBLE (-3850 5150);
FORCEPROP 1 LAST PACK_TYPE 6P10
J 0
(-3850 5150);
PAINT SKYBLUE (-3850 5150);
DISPLAY INVISIBLE (-3850 5150);
FORCEADD OSC_C..17
(-3700 3925);
FORCEPROP 1 LAST PART_NUMBER G63831-004
J 0
(-4150 3675);
DISPLAY 0.617021 (-4150 3675);
PAINT BLUE (-4150 3675);
FORCEPROP 2 LASTPIN (-3200 3825) $PN 3
J 0
(-3190 3835);
DISPLAY 0.617021 (-3190 3835);
PAINT ORANGE (-3190 3835);
FORCEPROP 2 LASTPIN (-3200 4025) $PN 5
J 0
(-3190 4035);
DISPLAY 0.617021 (-3190 4035);
PAINT ORANGE (-3190 4035);
FORCEPROP 2 LASTPIN (-3200 3925) $PN 4
J 0
(-3190 3935);
DISPLAY 0.617021 (-3190 3935);
PAINT ORANGE (-3190 3935);
FORCEPROP 1 LAST VALUE 156.25MHZ
J 0
(-4150 4150);
DISPLAY 0.617021 (-4150 4150);
PAINT SKYBLUE (-4150 4150);
FORCEPROP 1 LAST MATERIAL OSC
J 0
(-4150 4200);
DISPLAY 0.617021 (-4150 4200);
PAINT SKYBLUE (-4150 4200);
FORCEPROP 1 LAST LOCATION Y3F1
J 0
(-4150 4250);
DISPLAY 0.617021 (-4150 4250);
PAINT AQUA (-4150 4250);
FORCEPROP 2 LASTPIN (-4200 4025) $PN 6
J 2
(-4210 4035);
DISPLAY 0.617021 (-4210 4035);
PAINT ORANGE (-4210 4035);
FORCEPROP 2 LASTPIN (-4200 3925) $PN 1
J 2
(-4210 3935);
DISPLAY 0.617021 (-4210 3935);
PAINT ORANGE (-4210 3935);
FORCEPROP 2 LASTPIN (-4200 3825) $PN 2
J 2
(-4210 3835);
DISPLAY 0.617021 (-4210 3835);
PAINT ORANGE (-4210 3835);
FORCEPROP 2 LAST SEC 1
J 0
(-4150 4300);
DISPLAY 0.680851 (-4150 4300);
PAINT MONO (-4150 4300);
DISPLAY INVISIBLE (-4150 4300);
FORCEPROP 2 LAST CDS_LOCATION Y3F1
J 0
(-4150 4250);
DISPLAY 0.617021 (-4150 4250);
PAINT AQUA (-4150 4250);
DISPLAY INVISIBLE (-4150 4250);
FORCEPROP 2 LAST SEC_TYPE 6P10
J 0
(-4150 4300);
DISPLAY 1.021277 (-4150 4300);
PAINT ORANGE (-4150 4300);
DISPLAY INVISIBLE (-4150 4300);
FORCEPROP 1 LAST PACK_TYPE 6P10
J 0
(-4150 4300);
PAINT SKYBLUE (-4150 4300);
DISPLAY INVISIBLE (-4150 4300);
FORCEPROP 2 LAST CDS_LIB mstr_discrete
J 0
(-3700 3925);
PAINT ORANGE (-3700 3925);
DISPLAY INVISIBLE (-3700 3925);
FORCEPROP 1 LAST CDS_LMAN_SYM_OUTLINE -450,200,450,-200
J 0
(-3700 3925);
DISPLAY 0.468085 (-3700 3925);
PAINT GREEN (-3700 3925);
DISPLAY INVISIBLE (-3700 3925);
FORCEPROP 1 LAST PATH I72
J 0
(-3655 4155);
PAINT GREEN (-3655 4155);
DISPLAY INVISIBLE (-3655 4155);
FORCEADD OFFPAGE..1
(-550 5025);
FORCEPROP 2 LAST $XR0 194 
J 0
(-802 5025);
DISPLAY 0.638298 (-802 5025);
PAINT MONO (-802 5025);
FORCEPROP 2 LAST PATH I74
J 0
(-500 5100);
DISPLAY 1.021277 (-500 5100);
PAINT ORANGE (-500 5100);
DISPLAY INVISIBLE (-500 5100);
FORCEPROP 1 LAST COMMENT_BODY TRUE
J 0
(-425 4925);
DISPLAY 0.872340 (-425 4925);
PAINT GREEN (-425 4925);
DISPLAY INVISIBLE (-425 4925);
FORCEPROP 1 LAST OFFPAGE TRUE
J 0
(-225 4900);
DISPLAY 0.872340 (-225 4900);
PAINT GREEN (-225 4900);
DISPLAY INVISIBLE (-225 4900);
FORCEPROP 2 LAST CDS_LIB mstr_standard
J 0
(-550 5025);
PAINT ORANGE (-550 5025);
DISPLAY INVISIBLE (-550 5025);
FORCEADD OFFPAGE..1
(-550 4325);
FORCEPROP 2 LAST $XR0 194 
J 0
(-802 4325);
DISPLAY 0.638298 (-802 4325);
PAINT MONO (-802 4325);
FORCEPROP 2 LAST PATH I76
J 0
(-500 4400);
DISPLAY 1.021277 (-500 4400);
PAINT ORANGE (-500 4400);
DISPLAY INVISIBLE (-500 4400);
FORCEPROP 1 LAST COMMENT_BODY TRUE
J 0
(-425 4225);
DISPLAY 0.872340 (-425 4225);
PAINT GREEN (-425 4225);
DISPLAY INVISIBLE (-425 4225);
FORCEPROP 1 LAST OFFPAGE TRUE
J 0
(-225 4200);
DISPLAY 0.872340 (-225 4200);
PAINT GREEN (-225 4200);
DISPLAY INVISIBLE (-225 4200);
FORCEPROP 2 LAST CDS_LIB mstr_standard
J 0
(-550 4325);
PAINT ORANGE (-550 4325);
DISPLAY INVISIBLE (-550 4325);
FORCEADD OFFPAGE..2
(1675 4825);
FORCEPROP 2 LAST $XR0 22 
J 0
(1864 4825);
DISPLAY 0.638298 (1864 4825);
PAINT MONO (1864 4825);
FORCEPROP 1 LAST OFFPAGE TRUE
J 0
(2000 4700);
DISPLAY 0.872340 (2000 4700);
PAINT GREEN (2000 4700);
DISPLAY INVISIBLE (2000 4700);
FORCEPROP 2 LAST PATH I77
J 0
(1850 4900);
DISPLAY 1.021277 (1850 4900);
PAINT ORANGE (1850 4900);
DISPLAY INVISIBLE (1850 4900);
FORCEPROP 2 LAST CDS_LIB mstr_standard
J 0
(1675 4825);
PAINT ORANGE (1675 4825);
DISPLAY INVISIBLE (1675 4825);
FORCEPROP 1 LAST COMMENT_BODY TRUE
J 0
(1630 4730);
DISPLAY 0.872340 (1630 4730);
PAINT GREEN (1630 4730);
DISPLAY INVISIBLE (1630 4730);
FORCEADD RES..1
(525 4825);
FORCEPROP 1 LAST PART_NUMBER G21497-005
J 0
(675 4825);
DISPLAY 0.617021 (675 4825);
PAINT BLUE (675 4825);
FORCEPROP 1 LAST PACK_TYPE 0402
J 0
(725 4775);
DISPLAY 0.617021 (725 4775);
PAINT SKYBLUE (725 4775);
FORCEPROP 1 LAST VALUE 0.0
J 1
(300 4775);
DISPLAY 0.617021 (300 4775);
PAINT SKYBLUE (300 4775);
FORCEPROP 1 LAST MATERIAL EMPTY
J 1
(650 4775);
DISPLAY 0.617021 (650 4775);
PAINT RED (650 4775);
FORCEPROP 1 LAST LOCATION R6F10
J 0
(475 4875);
DISPLAY 0.617021 (475 4875);
PAINT AQUA (475 4875);
FORCEPROP 1 LAST TOLERANCE 5%
J 0
(500 4775);
DISPLAY 0.617021 (500 4775);
PAINT SKYBLUE (500 4775);
FORCEPROP 1 LASTPIN (625 4825) $PN 2
J 0
(587 4837);
DISPLAY 0.617021 (587 4837);
PAINT ORANGE (587 4837);
FORCEPROP 1 LASTPIN (425 4825) $PN 1
J 0
(437 4837);
DISPLAY 0.617021 (437 4837);
PAINT ORANGE (437 4837);
FORCEPROP 1 LAST WATTAGE 1/16W
J 0
(350 4775);
DISPLAY 0.617021 (350 4775);
PAINT SKYBLUE (350 4775);
FORCEPROP 2 LAST CDS_LIB mstr_discrete
J 0
(525 4825);
PAINT ORANGE (525 4825);
DISPLAY INVISIBLE (525 4825);
FORCEPROP 2 LAST SEC_TYPE 0402
J 0
(475 5025);
DISPLAY 1.021277 (475 5025);
PAINT ORANGE (475 5025);
DISPLAY INVISIBLE (475 5025);
FORCEPROP 2 LAST SEC 1
J 0
(475 5025);
DISPLAY 0.680851 (475 5025);
PAINT MONO (475 5025);
DISPLAY INVISIBLE (475 5025);
FORCEPROP 1 LAST PATH I78
J 0
(475 4975);
DISPLAY 0.978723 (475 4975);
PAINT WHITE (475 4975);
DISPLAY INVISIBLE (475 4975);
FORCEADD RES..1
(525 4125);
FORCEPROP 1 LAST WATTAGE 1/16W
J 0
(350 4075);
DISPLAY 0.617021 (350 4075);
PAINT SKYBLUE (350 4075);
FORCEPROP 1 LAST LOCATION R6F11
J 0
(475 4175);
DISPLAY 0.617021 (475 4175);
PAINT AQUA (475 4175);
FORCEPROP 1 LAST PART_NUMBER G21497-005
J 0
(650 4125);
DISPLAY 0.617021 (650 4125);
PAINT BLUE (650 4125);
FORCEPROP 1 LASTPIN (625 4125) $PN 2
J 0
(587 4137);
DISPLAY 0.617021 (587 4137);
PAINT ORANGE (587 4137);
FORCEPROP 1 LASTPIN (425 4125) $PN 1
J 0
(437 4137);
DISPLAY 0.617021 (437 4137);
PAINT ORANGE (437 4137);
FORCEPROP 1 LAST MATERIAL EMPTY
J 1
(650 4075);
DISPLAY 0.617021 (650 4075);
PAINT RED (650 4075);
FORCEPROP 1 LAST VALUE 0.0
J 1
(300 4075);
DISPLAY 0.617021 (300 4075);
PAINT SKYBLUE (300 4075);
FORCEPROP 1 LAST PACK_TYPE 0402
J 0
(725 4075);
DISPLAY 0.617021 (725 4075);
PAINT SKYBLUE (725 4075);
FORCEPROP 1 LAST TOLERANCE 5%
J 0
(500 4075);
DISPLAY 0.617021 (500 4075);
PAINT SKYBLUE (500 4075);
FORCEPROP 2 LAST CDS_LIB mstr_discrete
J 0
(525 4125);
PAINT ORANGE (525 4125);
DISPLAY INVISIBLE (525 4125);
FORCEPROP 2 LAST SEC_TYPE 0402
J 0
(475 4325);
DISPLAY 1.021277 (475 4325);
PAINT ORANGE (475 4325);
DISPLAY INVISIBLE (475 4325);
FORCEPROP 2 LAST SEC 1
J 0
(475 4325);
DISPLAY 0.680851 (475 4325);
PAINT MONO (475 4325);
DISPLAY INVISIBLE (475 4325);
FORCEPROP 1 LAST PATH I79
J 0
(475 4275);
DISPLAY 0.978723 (475 4275);
PAINT WHITE (475 4275);
DISPLAY INVISIBLE (475 4275);
FORCEADD OFFPAGE..2
(1675 4125);
FORCEPROP 2 LAST $XR0 22 
J 0
(1864 4125);
DISPLAY 0.638298 (1864 4125);
PAINT MONO (1864 4125);
FORCEPROP 2 LAST PATH I80
J 0
(1850 4200);
DISPLAY 1.021277 (1850 4200);
PAINT ORANGE (1850 4200);
DISPLAY INVISIBLE (1850 4200);
FORCEPROP 2 LAST CDS_LIB mstr_standard
J 0
(1675 4125);
PAINT ORANGE (1675 4125);
DISPLAY INVISIBLE (1675 4125);
FORCEPROP 1 LAST OFFPAGE TRUE
J 0
(2000 4000);
DISPLAY 0.872340 (2000 4000);
PAINT GREEN (2000 4000);
DISPLAY INVISIBLE (2000 4000);
FORCEPROP 1 LAST COMMENT_BODY TRUE
J 0
(1630 4030);
DISPLAY 0.872340 (1630 4030);
PAINT GREEN (1630 4030);
DISPLAY INVISIBLE (1630 4030);
FORCEADD OFFPAGE..1
(-550 3625);
FORCEPROP 2 LAST $XR0 193 
J 0
(-802 3625);
DISPLAY 0.638298 (-802 3625);
PAINT MONO (-802 3625);
FORCEPROP 1 LAST OFFPAGE TRUE
J 0
(-225 3500);
DISPLAY 0.872340 (-225 3500);
PAINT GREEN (-225 3500);
DISPLAY INVISIBLE (-225 3500);
FORCEPROP 1 LAST COMMENT_BODY TRUE
J 0
(-425 3525);
DISPLAY 0.872340 (-425 3525);
PAINT GREEN (-425 3525);
DISPLAY INVISIBLE (-425 3525);
FORCEPROP 2 LAST PATH I81
J 0
(-500 3700);
DISPLAY 1.021277 (-500 3700);
PAINT ORANGE (-500 3700);
DISPLAY INVISIBLE (-500 3700);
FORCEPROP 2 LAST CDS_LIB mstr_standard
J 0
(-550 3625);
PAINT ORANGE (-550 3625);
DISPLAY INVISIBLE (-550 3625);
FORCEADD OFFPAGE..2
(1675 3425);
FORCEPROP 2 LAST $XR0 56 
J 0
(1864 3425);
DISPLAY 0.638298 (1864 3425);
PAINT MONO (1864 3425);
FORCEPROP 2 LAST PATH I83
J 0
(1850 3500);
DISPLAY 1.021277 (1850 3500);
PAINT ORANGE (1850 3500);
DISPLAY INVISIBLE (1850 3500);
FORCEPROP 1 LAST OFFPAGE TRUE
J 0
(2000 3300);
DISPLAY 0.872340 (2000 3300);
PAINT GREEN (2000 3300);
DISPLAY INVISIBLE (2000 3300);
FORCEPROP 2 LAST CDS_LIB mstr_standard
J 0
(1675 3425);
PAINT ORANGE (1675 3425);
DISPLAY INVISIBLE (1675 3425);
FORCEPROP 1 LAST COMMENT_BODY TRUE
J 0
(1630 3330);
DISPLAY 0.872340 (1630 3330);
PAINT GREEN (1630 3330);
DISPLAY INVISIBLE (1630 3330);
FORCEADD RES..1
(525 3425);
FORCEPROP 1 LAST PART_NUMBER G21497-005
J 0
(650 3425);
DISPLAY 0.617021 (650 3425);
PAINT BLUE (650 3425);
FORCEPROP 1 LAST LOCATION R3F5
J 0
(475 3475);
DISPLAY 0.617021 (475 3475);
PAINT AQUA (475 3475);
FORCEPROP 1 LAST MATERIAL EMPTY
J 1
(650 3375);
DISPLAY 0.617021 (650 3375);
PAINT RED (650 3375);
FORCEPROP 1 LAST PACK_TYPE 0402
J 1
(775 3375);
DISPLAY 0.617021 (775 3375);
PAINT SKYBLUE (775 3375);
FORCEPROP 1 LASTPIN (625 3425) $PN 2
J 0
(587 3437);
DISPLAY 0.617021 (587 3437);
PAINT ORANGE (587 3437);
FORCEPROP 1 LAST TOLERANCE 5%
J 0
(500 3375);
DISPLAY 0.617021 (500 3375);
PAINT SKYBLUE (500 3375);
FORCEPROP 1 LASTPIN (425 3425) $PN 1
J 0
(437 3437);
DISPLAY 0.617021 (437 3437);
PAINT ORANGE (437 3437);
FORCEPROP 1 LAST VALUE 0.0
J 1
(300 3375);
DISPLAY 0.617021 (300 3375);
PAINT SKYBLUE (300 3375);
FORCEPROP 1 LAST WATTAGE 1/16W
J 0
(350 3375);
DISPLAY 0.617021 (350 3375);
PAINT SKYBLUE (350 3375);
FORCEPROP 2 LAST CDS_LIB mstr_discrete
J 0
(525 3425);
PAINT ORANGE (525 3425);
DISPLAY INVISIBLE (525 3425);
FORCEPROP 2 LAST SEC_TYPE 0402
J 0
(475 3625);
DISPLAY 1.021277 (475 3625);
PAINT ORANGE (475 3625);
DISPLAY INVISIBLE (475 3625);
FORCEPROP 2 LAST SEC 1
J 0
(475 3625);
DISPLAY 0.680851 (475 3625);
PAINT MONO (475 3625);
DISPLAY INVISIBLE (475 3625);
FORCEPROP 1 LAST PATH I84
J 0
(475 3575);
DISPLAY 0.978723 (475 3575);
PAINT WHITE (475 3575);
DISPLAY INVISIBLE (475 3575);
FORCEADD OFFPAGE..1
(-550 2925);
FORCEPROP 2 LAST $XR0 193 
J 0
(-802 2925);
DISPLAY 0.638298 (-802 2925);
PAINT MONO (-802 2925);
FORCEPROP 1 LAST OFFPAGE TRUE
J 0
(-225 2800);
DISPLAY 0.872340 (-225 2800);
PAINT GREEN (-225 2800);
DISPLAY INVISIBLE (-225 2800);
FORCEPROP 1 LAST COMMENT_BODY TRUE
J 0
(-425 2825);
DISPLAY 0.872340 (-425 2825);
PAINT GREEN (-425 2825);
DISPLAY INVISIBLE (-425 2825);
FORCEPROP 2 LAST PATH I86
J 0
(-500 3000);
DISPLAY 1.021277 (-500 3000);
PAINT ORANGE (-500 3000);
DISPLAY INVISIBLE (-500 3000);
FORCEPROP 2 LAST CDS_LIB mstr_standard
J 0
(-550 2925);
PAINT ORANGE (-550 2925);
DISPLAY INVISIBLE (-550 2925);
FORCEADD OFFPAGE..2
(1675 2725);
FORCEPROP 2 LAST $XR0 56 
J 0
(1864 2725);
DISPLAY 0.638298 (1864 2725);
PAINT MONO (1864 2725);
FORCEPROP 2 LAST PATH I87
J 0
(1850 2800);
DISPLAY 1.021277 (1850 2800);
PAINT ORANGE (1850 2800);
DISPLAY INVISIBLE (1850 2800);
FORCEPROP 2 LAST CDS_LIB mstr_standard
J 0
(1675 2725);
PAINT ORANGE (1675 2725);
DISPLAY INVISIBLE (1675 2725);
FORCEPROP 1 LAST COMMENT_BODY TRUE
J 0
(1630 2630);
DISPLAY 0.872340 (1630 2630);
PAINT GREEN (1630 2630);
DISPLAY INVISIBLE (1630 2630);
FORCEPROP 1 LAST OFFPAGE TRUE
J 0
(2000 2600);
DISPLAY 0.872340 (2000 2600);
PAINT GREEN (2000 2600);
DISPLAY INVISIBLE (2000 2600);
FORCEADD RES..1
(525 2725);
FORCEPROP 1 LAST PART_NUMBER G21497-005
J 0
(650 2725);
DISPLAY 0.617021 (650 2725);
PAINT BLUE (650 2725);
FORCEPROP 1 LAST LOCATION R3F6
J 0
(475 2775);
DISPLAY 0.617021 (475 2775);
PAINT AQUA (475 2775);
FORCEPROP 1 LAST MATERIAL EMPTY
J 1
(650 2675);
DISPLAY 0.617021 (650 2675);
PAINT RED (650 2675);
FORCEPROP 1 LAST TOLERANCE 5%
J 0
(500 2675);
DISPLAY 0.617021 (500 2675);
PAINT SKYBLUE (500 2675);
FORCEPROP 1 LASTPIN (625 2725) $PN 2
J 0
(587 2737);
DISPLAY 0.617021 (587 2737);
PAINT ORANGE (587 2737);
FORCEPROP 1 LASTPIN (425 2725) $PN 1
J 0
(437 2737);
DISPLAY 0.617021 (437 2737);
PAINT ORANGE (437 2737);
FORCEPROP 1 LAST WATTAGE 1/16W
J 0
(350 2675);
DISPLAY 0.617021 (350 2675);
PAINT SKYBLUE (350 2675);
FORCEPROP 1 LAST VALUE 0.0
J 1
(300 2675);
DISPLAY 0.617021 (300 2675);
PAINT SKYBLUE (300 2675);
FORCEPROP 1 LAST PACK_TYPE 0402
J 1
(775 2675);
DISPLAY 0.617021 (775 2675);
PAINT SKYBLUE (775 2675);
FORCEPROP 2 LAST CDS_LIB mstr_discrete
J 0
(525 2725);
PAINT ORANGE (525 2725);
DISPLAY INVISIBLE (525 2725);
FORCEPROP 2 LAST SEC_TYPE 0402
J 0
(475 2925);
DISPLAY 1.021277 (475 2925);
PAINT ORANGE (475 2925);
DISPLAY INVISIBLE (475 2925);
FORCEPROP 2 LAST SEC 1
J 0
(475 2925);
DISPLAY 0.680851 (475 2925);
PAINT MONO (475 2925);
DISPLAY INVISIBLE (475 2925);
FORCEPROP 1 LAST PATH I88
J 0
(475 2875);
DISPLAY 0.978723 (475 2875);
PAINT WHITE (475 2875);
DISPLAY INVISIBLE (475 2875);
FORCEADD OFFPAGE..2
(1700 1100);
FORCEPROP 2 LAST $XR0 193 
J 0
(1889 1100);
DISPLAY 0.638298 (1889 1100);
PAINT MONO (1889 1100);
FORCEPROP 1 LAST OFFPAGE TRUE
J 0
(2025 975);
DISPLAY 0.872340 (2025 975);
PAINT GREEN (2025 975);
DISPLAY INVISIBLE (2025 975);
FORCEPROP 1 LAST COMMENT_BODY TRUE
J 0
(1655 1005);
DISPLAY 0.872340 (1655 1005);
PAINT GREEN (1655 1005);
DISPLAY INVISIBLE (1655 1005);
FORCEPROP 2 LAST CDS_LIB mstr_standard
J 0
(1700 1100);
PAINT ORANGE (1700 1100);
DISPLAY INVISIBLE (1700 1100);
FORCEPROP 2 LAST PATH I89
J 0
(1875 1175);
DISPLAY 1.021277 (1875 1175);
PAINT ORANGE (1875 1175);
DISPLAY INVISIBLE (1875 1175);
FORCEADD OFFPAGE..2
(1700 2200);
FORCEPROP 2 LAST $XR0 104 
J 0
(1889 2200);
DISPLAY 0.638298 (1889 2200);
PAINT MONO (1889 2200);
FORCEPROP 1 LAST COMMENT_BODY TRUE
J 0
(1655 2105);
DISPLAY 0.872340 (1655 2105);
PAINT GREEN (1655 2105);
DISPLAY INVISIBLE (1655 2105);
FORCEPROP 2 LAST CDS_LIB mstr_standard
J 0
(1700 2200);
PAINT ORANGE (1700 2200);
DISPLAY INVISIBLE (1700 2200);
FORCEPROP 2 LAST PATH I90
J 0
(1875 2275);
DISPLAY 1.021277 (1875 2275);
PAINT ORANGE (1875 2275);
DISPLAY INVISIBLE (1875 2275);
FORCEPROP 1 LAST OFFPAGE TRUE
J 0
(2025 2075);
DISPLAY 0.872340 (2025 2075);
PAINT GREEN (2025 2075);
DISPLAY INVISIBLE (2025 2075);
FORCEADD OFFPAGE..2
(1700 1800);
FORCEPROP 2 LAST $XR0 194 
J 0
(1889 1800);
DISPLAY 0.638298 (1889 1800);
PAINT MONO (1889 1800);
FORCEPROP 1 LAST COMMENT_BODY TRUE
J 0
(1655 1705);
DISPLAY 0.872340 (1655 1705);
PAINT GREEN (1655 1705);
DISPLAY INVISIBLE (1655 1705);
FORCEPROP 2 LAST CDS_LIB mstr_standard
J 0
(1700 1800);
PAINT ORANGE (1700 1800);
DISPLAY INVISIBLE (1700 1800);
FORCEPROP 2 LAST PATH I91
J 0
(1875 1875);
DISPLAY 1.021277 (1875 1875);
PAINT ORANGE (1875 1875);
DISPLAY INVISIBLE (1875 1875);
FORCEPROP 1 LAST OFFPAGE TRUE
J 0
(2025 1675);
DISPLAY 0.872340 (2025 1675);
PAINT GREEN (2025 1675);
DISPLAY INVISIBLE (2025 1675);
FORCEADD OFFPAGE..2
(1700 1500);
FORCEPROP 2 LAST $XR0 104 
J 0
(1889 1500);
DISPLAY 0.638298 (1889 1500);
PAINT MONO (1889 1500);
FORCEPROP 1 LAST COMMENT_BODY TRUE
J 0
(1655 1405);
DISPLAY 0.872340 (1655 1405);
PAINT GREEN (1655 1405);
DISPLAY INVISIBLE (1655 1405);
FORCEPROP 1 LAST OFFPAGE TRUE
J 0
(2025 1375);
DISPLAY 0.872340 (2025 1375);
PAINT GREEN (2025 1375);
DISPLAY INVISIBLE (2025 1375);
FORCEPROP 2 LAST CDS_LIB mstr_standard
J 0
(1700 1500);
PAINT ORANGE (1700 1500);
DISPLAY INVISIBLE (1700 1500);
FORCEPROP 2 LAST PATH I92
J 0
(1875 1575);
DISPLAY 1.021277 (1875 1575);
PAINT ORANGE (1875 1575);
DISPLAY INVISIBLE (1875 1575);
FORCEADD RES..1
(550 2200);
FORCEPROP 1 LAST WATTAGE 1/16W
J 0
(375 2150);
DISPLAY 0.617021 (375 2150);
PAINT SKYBLUE (375 2150);
FORCEPROP 1 LAST VALUE 0.0
J 1
(325 2150);
DISPLAY 0.617021 (325 2150);
PAINT SKYBLUE (325 2150);
FORCEPROP 1 LASTPIN (450 2200) $PN 1
J 0
(462 2212);
DISPLAY 0.617021 (462 2212);
PAINT ORANGE (462 2212);
FORCEPROP 1 LAST LOCATION R8D43
J 0
(500 2250);
DISPLAY 0.617021 (500 2250);
PAINT AQUA (500 2250);
FORCEPROP 1 LAST TOLERANCE 5%
J 0
(525 2150);
DISPLAY 0.617021 (525 2150);
PAINT SKYBLUE (525 2150);
FORCEPROP 1 LASTPIN (650 2200) $PN 2
J 0
(612 2212);
DISPLAY 0.617021 (612 2212);
PAINT ORANGE (612 2212);
FORCEPROP 1 LAST MATERIAL CHIP
J 1
(675 2150);
DISPLAY 0.617021 (675 2150);
PAINT SKYBLUE (675 2150);
FORCEPROP 1 LAST PACK_TYPE 0402
J 1
(800 2150);
DISPLAY 0.617021 (800 2150);
PAINT SKYBLUE (800 2150);
FORCEPROP 1 LAST PART_NUMBER G21497-005
J 0
(675 2200);
DISPLAY 0.617021 (675 2200);
PAINT BLUE (675 2200);
FORCEPROP 0 LAST ROOM CLOCK_CPU1_OSC
J 0
(500 2350);
DISPLAY 1.021277 (500 2350);
PAINT ORANGE (500 2350);
DISPLAY INVISIBLE (500 2350);
FORCEPROP 1 LAST PATH I93
J 0
(500 2350);
DISPLAY 0.978723 (500 2350);
PAINT WHITE (500 2350);
DISPLAY INVISIBLE (500 2350);
FORCEPROP 2 LAST SEC 1
J 0
(500 2400);
DISPLAY 0.680851 (500 2400);
PAINT MONO (500 2400);
DISPLAY INVISIBLE (500 2400);
FORCEPROP 2 LAST SEC_TYPE 0402
J 0
(500 2400);
DISPLAY 1.021277 (500 2400);
PAINT ORANGE (500 2400);
DISPLAY INVISIBLE (500 2400);
FORCEPROP 2 LAST CDS_LIB mstr_discrete
J 0
(550 2200);
PAINT ORANGE (550 2200);
DISPLAY INVISIBLE (550 2200);
FORCEADD RES..1
(550 2000);
FORCEPROP 1 LAST MATERIAL EMPTY
J 1
(675 1950);
DISPLAY 0.617021 (675 1950);
PAINT RED (675 1950);
FORCEPROP 1 LAST LOCATION R7D40
J 0
(500 2050);
DISPLAY 0.617021 (500 2050);
PAINT AQUA (500 2050);
FORCEPROP 1 LASTPIN (450 2000) $PN 1
J 0
(462 2012);
DISPLAY 0.617021 (462 2012);
PAINT ORANGE (462 2012);
FORCEPROP 1 LAST TOLERANCE 5%
J 0
(525 1950);
DISPLAY 0.617021 (525 1950);
PAINT SKYBLUE (525 1950);
FORCEPROP 1 LASTPIN (650 2000) $PN 2
J 0
(612 2012);
DISPLAY 0.617021 (612 2012);
PAINT ORANGE (612 2012);
FORCEPROP 1 LAST PACK_TYPE 0402
J 1
(800 1950);
DISPLAY 0.617021 (800 1950);
PAINT SKYBLUE (800 1950);
FORCEPROP 1 LAST PART_NUMBER G21497-005
J 0
(675 2000);
DISPLAY 0.617021 (675 2000);
PAINT BLUE (675 2000);
FORCEPROP 1 LAST WATTAGE 1/16W
J 0
(375 1950);
DISPLAY 0.617021 (375 1950);
PAINT SKYBLUE (375 1950);
FORCEPROP 1 LAST VALUE 0.0
J 1
(325 1950);
DISPLAY 0.617021 (325 1950);
PAINT SKYBLUE (325 1950);
FORCEPROP 2 LAST CDS_LIB mstr_discrete
J 0
(550 2000);
PAINT ORANGE (550 2000);
DISPLAY INVISIBLE (550 2000);
FORCEPROP 1 LAST PATH I94
J 0
(500 2150);
DISPLAY 0.978723 (500 2150);
PAINT WHITE (500 2150);
DISPLAY INVISIBLE (500 2150);
FORCEPROP 2 LAST SEC 1
J 0
(500 2200);
DISPLAY 0.680851 (500 2200);
PAINT MONO (500 2200);
DISPLAY INVISIBLE (500 2200);
FORCEPROP 2 LAST SEC_TYPE 0402
J 0
(500 2200);
DISPLAY 1.021277 (500 2200);
PAINT ORANGE (500 2200);
DISPLAY INVISIBLE (500 2200);
FORCEPROP 2 LAST ROOM CLOCK_CPU1_OSC
J 0
(1025 2100);
DISPLAY 1.021277 (1025 2100);
PAINT ORANGE (1025 2100);
DISPLAY INVISIBLE (1025 2100);
FORCEADD RES..1
(550 1500);
FORCEPROP 1 LAST PART_NUMBER G21497-005
J 0
(675 1500);
DISPLAY 0.617021 (675 1500);
PAINT BLUE (675 1500);
FORCEPROP 1 LAST PACK_TYPE 0402
J 1
(800 1450);
DISPLAY 0.617021 (800 1450);
PAINT SKYBLUE (800 1450);
FORCEPROP 1 LAST VALUE 0.0
J 1
(325 1450);
DISPLAY 0.617021 (325 1450);
PAINT SKYBLUE (325 1450);
FORCEPROP 1 LASTPIN (450 1500) $PN 1
J 0
(462 1512);
DISPLAY 0.617021 (462 1512);
PAINT ORANGE (462 1512);
FORCEPROP 1 LAST WATTAGE 1/16W
J 0
(375 1450);
DISPLAY 0.617021 (375 1450);
PAINT SKYBLUE (375 1450);
FORCEPROP 1 LAST LOCATION R7D36
J 0
(500 1550);
DISPLAY 0.617021 (500 1550);
PAINT AQUA (500 1550);
FORCEPROP 1 LAST TOLERANCE 5%
J 0
(525 1450);
DISPLAY 0.617021 (525 1450);
PAINT SKYBLUE (525 1450);
FORCEPROP 1 LAST MATERIAL CHIP
J 1
(675 1450);
DISPLAY 0.617021 (675 1450);
PAINT SKYBLUE (675 1450);
FORCEPROP 1 LASTPIN (650 1500) $PN 2
J 0
(612 1512);
DISPLAY 0.617021 (612 1512);
PAINT ORANGE (612 1512);
FORCEPROP 0 LAST ROOM CLOCK_CPU1_OSC
J 0
(500 1650);
DISPLAY 1.021277 (500 1650);
PAINT ORANGE (500 1650);
DISPLAY INVISIBLE (500 1650);
FORCEPROP 1 LAST PATH I96
J 0
(500 1650);
DISPLAY 0.978723 (500 1650);
PAINT WHITE (500 1650);
DISPLAY INVISIBLE (500 1650);
FORCEPROP 2 LAST SEC 1
J 0
(500 1700);
DISPLAY 0.680851 (500 1700);
PAINT MONO (500 1700);
DISPLAY INVISIBLE (500 1700);
FORCEPROP 2 LAST SEC_TYPE 0402
J 0
(500 1700);
DISPLAY 1.021277 (500 1700);
PAINT ORANGE (500 1700);
DISPLAY INVISIBLE (500 1700);
FORCEPROP 2 LAST CDS_LIB mstr_discrete
J 0
(550 1500);
PAINT ORANGE (550 1500);
DISPLAY INVISIBLE (550 1500);
FORCEADD RES..1
(550 1300);
FORCEPROP 1 LAST PACK_TYPE 0402
J 1
(800 1250);
DISPLAY 0.617021 (800 1250);
PAINT SKYBLUE (800 1250);
FORCEPROP 1 LAST MATERIAL EMPTY
J 1
(675 1250);
DISPLAY 0.617021 (675 1250);
PAINT RED (675 1250);
FORCEPROP 1 LAST PART_NUMBER G21497-005
J 0
(675 1300);
DISPLAY 0.617021 (675 1300);
PAINT BLUE (675 1300);
FORCEPROP 1 LAST TOLERANCE 5%
J 0
(525 1250);
DISPLAY 0.617021 (525 1250);
PAINT SKYBLUE (525 1250);
FORCEPROP 1 LAST VALUE 0.0
J 1
(325 1250);
DISPLAY 0.617021 (325 1250);
PAINT SKYBLUE (325 1250);
FORCEPROP 1 LASTPIN (450 1300) $PN 1
J 0
(462 1312);
DISPLAY 0.617021 (462 1312);
PAINT ORANGE (462 1312);
FORCEPROP 1 LAST WATTAGE 1/16W
J 0
(375 1250);
DISPLAY 0.617021 (375 1250);
PAINT SKYBLUE (375 1250);
FORCEPROP 1 LAST LOCATION R7D38
J 0
(500 1350);
DISPLAY 0.617021 (500 1350);
PAINT AQUA (500 1350);
FORCEPROP 1 LASTPIN (650 1300) $PN 2
J 0
(612 1312);
DISPLAY 0.617021 (612 1312);
PAINT ORANGE (612 1312);
FORCEPROP 1 LAST PATH I97
J 0
(500 1450);
DISPLAY 0.978723 (500 1450);
PAINT WHITE (500 1450);
DISPLAY INVISIBLE (500 1450);
FORCEPROP 2 LAST SEC 1
J 0
(500 1500);
DISPLAY 0.680851 (500 1500);
PAINT MONO (500 1500);
DISPLAY INVISIBLE (500 1500);
FORCEPROP 2 LAST SEC_TYPE 0402
J 0
(500 1500);
DISPLAY 1.021277 (500 1500);
PAINT ORANGE (500 1500);
DISPLAY INVISIBLE (500 1500);
FORCEPROP 2 LAST CDS_LIB mstr_discrete
J 0
(550 1300);
PAINT ORANGE (550 1300);
DISPLAY INVISIBLE (550 1300);
FORCEPROP 2 LAST ROOM CLOCK_CPU1_OSC
J 0
(1025 1400);
DISPLAY 1.021277 (1025 1400);
PAINT ORANGE (1025 1400);
DISPLAY INVISIBLE (1025 1400);
FORCEADD OFFPAGE..1
(-525 2200);
FORCEPROP 2 LAST $XR0 190 
J 0
(-777 2200);
DISPLAY 0.638298 (-777 2200);
PAINT MONO (-777 2200);
FORCEPROP 2 LAST CDS_LIB mstr_standard
J 0
(-525 2200);
PAINT ORANGE (-525 2200);
DISPLAY INVISIBLE (-525 2200);
FORCEPROP 2 LAST PATH I99
J 0
(-475 2275);
DISPLAY 1.021277 (-475 2275);
PAINT ORANGE (-475 2275);
DISPLAY INVISIBLE (-475 2275);
FORCEPROP 1 LAST COMMENT_BODY TRUE
J 0
(-400 2100);
DISPLAY 0.872340 (-400 2100);
PAINT GREEN (-400 2100);
DISPLAY INVISIBLE (-400 2100);
FORCEPROP 1 LAST OFFPAGE TRUE
J 0
(-200 2075);
DISPLAY 0.872340 (-200 2075);
PAINT GREEN (-200 2075);
DISPLAY INVISIBLE (-200 2075);
FORCEADD DNS..2
(530 4820);
PAINT RED (530 4820);
FORCEPROP 2 LAST CDS_LIB mstr_misc
J 0
(530 4820);
PAINT ORANGE (530 4820);
DISPLAY INVISIBLE (530 4820);
FORCEPROP 1 LAST COMMENT_BODY TRUE
R 1
J 0
(605 4595);
DISPLAY 0.872340 (605 4595);
PAINT GREEN (605 4595);
DISPLAY INVISIBLE (605 4595);
FORCEADD DNS..2
(530 4120);
PAINT RED (530 4120);
FORCEPROP 2 LAST CDS_LIB mstr_misc
J 0
(530 4120);
PAINT ORANGE (530 4120);
DISPLAY INVISIBLE (530 4120);
FORCEPROP 1 LAST COMMENT_BODY TRUE
R 1
J 0
(605 3895);
DISPLAY 0.872340 (605 3895);
PAINT GREEN (605 3895);
DISPLAY INVISIBLE (605 3895);
FORCEADD DNS..2
(530 2720);
PAINT RED (530 2720);
FORCEPROP 2 LAST CDS_LIB mstr_misc
J 0
(530 2720);
PAINT ORANGE (530 2720);
DISPLAY INVISIBLE (530 2720);
FORCEPROP 1 LAST COMMENT_BODY TRUE
R 1
J 0
(605 2495);
DISPLAY 0.872340 (605 2495);
PAINT GREEN (605 2495);
DISPLAY INVISIBLE (605 2495);
FORCEADD DNS..2
(530 3420);
PAINT RED (530 3420);
FORCEPROP 2 LAST CDS_LIB mstr_misc
J 0
(530 3420);
PAINT ORANGE (530 3420);
DISPLAY INVISIBLE (530 3420);
FORCEPROP 1 LAST COMMENT_BODY TRUE
R 1
J 0
(605 3195);
DISPLAY 0.872340 (605 3195);
PAINT GREEN (605 3195);
DISPLAY INVISIBLE (605 3195);
FORCEADD DNS..2
(530 4320);
PAINT RED (530 4320);
FORCEPROP 2 LAST CDS_LIB mstr_misc
J 0
(530 4320);
PAINT ORANGE (530 4320);
DISPLAY INVISIBLE (530 4320);
FORCEPROP 1 LAST COMMENT_BODY TRUE
R 1
J 0
(605 4095);
DISPLAY 0.872340 (605 4095);
PAINT GREEN (605 4095);
DISPLAY INVISIBLE (605 4095);
FORCEADD DNS..2
(555 1995);
PAINT RED (555 1995);
FORCEPROP 1 LAST COMMENT_BODY TRUE
R 1
J 0
(630 1770);
DISPLAY 0.872340 (630 1770);
PAINT GREEN (630 1770);
DISPLAY INVISIBLE (630 1770);
FORCEPROP 2 LAST CDS_LIB mstr_misc
J 0
(555 1995);
PAINT ORANGE (555 1995);
DISPLAY INVISIBLE (555 1995);
FORCEADD INTEL_CORP_BPAGE..1
(2650 500);
FORCEPROP 1 LAST CDS_CON_LAST_MODIFIED Fri Jun 16 17:48:41 2017
J 0
(1225 825);
DISPLAY 0.617021 (1225 825);
PAINT ORANGE (1225 825);
DISPLAY INVISIBLE (1225 825);
FORCEPROP 1 LAST CUSTOM_TXT_CDS <CURRENT_DESIGN_SHEET> OF <TOTAL_DESIGN_SHEETS>
J 0
(2150 525);
PAINT ORANGE (2150 525);
FORCEPROP 1 LAST CUSTOM_TXT_CDS <CON_LAST_MODIFIED>
J 0
(-1350 600);
PAINT ORANGE (-1350 600);
FORCEPROP 2 LAST CUSTOM_TXT_CDS <XR_PAGE_TITLE>
J 0
(-5240 5750);
DISPLAY 0.638298 (-5240 5750);
PAINT PINK (-5240 5750);
DISPLAY INVISIBLE (-5240 5750);
FORCEPROP 1 LAST SCH_TITLE HFI OSCILLATORS
J 0
(-5300 550);
DISPLAY 1.212766 (-5300 550);
PAINT GREEN (-5300 550);
FORCEPROP 2 LAST PAGE_BORDER TRUE
J 0
(-5240 5750);
DISPLAY 0.531915 (-5240 5750);
PAINT PINK (-5240 5750);
DISPLAY INVISIBLE (-5240 5750);
FORCEPROP 1 LAST COMMENT_BODY TRUE
J 0
(2660 510);
DISPLAY 0.297872 (2660 510);
PAINT GREEN (2660 510);
DISPLAY INVISIBLE (2660 510);
FORCEPROP 2 LAST CDS_LIB mstr_symbols
J 0
(2650 500);
DISPLAY 0.617021 (2650 500);
PAINT MONO (2650 500);
DISPLAY INVISIBLE (2650 500);
FORCEPROP 2 LAST CDS_XR_PAGE_TITLE CR-104 : @BASEBOARD_FAB2_LIB.BASEBOARD_FAB2(SCH_1):PAGE104
J 0
(-5240 5750);
DISPLAY 0.638298 (-5240 5750);
PAINT PINK (-5240 5750);
DISPLAY INVISIBLE (-5240 5750);
FORCEADD CAD_NOTE..1
(-1350 2625);
FORCEPROP 0 LAST L1 USE A COMMON FOOTPRINT FOR RESISTORS
J 0
(-1475 2475);
DISPLAY 1.021277 (-1475 2475);
PAINT ORANGE (-1475 2475);
FORCEPROP 1 LAST COMMENT_BODY TRUE
J 0
(-1325 2725);
DISPLAY 0.978723 (-1325 2725);
PAINT ORANGE (-1325 2725);
DISPLAY INVISIBLE (-1325 2725);
FORCEPROP 2 LAST CDS_LIB mstr_symbols
J 0
(-1350 2625);
PAINT ORANGE (-1350 2625);
DISPLAY INVISIBLE (-1350 2625);
FORCEADD DNS..2
(530 3620);
PAINT RED (530 3620);
FORCEPROP 2 LAST CDS_LIB mstr_misc
J 0
(530 3620);
PAINT ORANGE (530 3620);
DISPLAY INVISIBLE (530 3620);
FORCEPROP 1 LAST COMMENT_BODY TRUE
R 1
J 0
(605 3395);
DISPLAY 0.872340 (605 3395);
PAINT GREEN (605 3395);
DISPLAY INVISIBLE (605 3395);
FORCEADD DNS..2
(530 5020);
PAINT RED (530 5020);
FORCEPROP 2 LAST CDS_LIB mstr_misc
J 0
(530 5020);
PAINT ORANGE (530 5020);
DISPLAY INVISIBLE (530 5020);
FORCEPROP 1 LAST COMMENT_BODY TRUE
R 1
J 0
(605 4795);
DISPLAY 0.872340 (605 4795);
PAINT GREEN (605 4795);
DISPLAY INVISIBLE (605 4795);
FORCEADD DNS..2
(530 2920);
PAINT RED (530 2920);
FORCEPROP 2 LAST CDS_LIB mstr_misc
J 0
(530 2920);
PAINT ORANGE (530 2920);
DISPLAY INVISIBLE (530 2920);
FORCEPROP 1 LAST COMMENT_BODY TRUE
R 1
J 0
(605 2695);
DISPLAY 0.872340 (605 2695);
PAINT GREEN (605 2695);
DISPLAY INVISIBLE (605 2695);
FORCEADD DNS..2
(555 1295);
PAINT RED (555 1295);
FORCEPROP 1 LAST COMMENT_BODY TRUE
R 1
J 0
(630 1070);
DISPLAY 0.872340 (630 1070);
PAINT GREEN (630 1070);
DISPLAY INVISIBLE (630 1070);
FORCEPROP 2 LAST CDS_LIB mstr_misc
J 0
(555 1295);
PAINT ORANGE (555 1295);
DISPLAY INVISIBLE (555 1295);
WIRE 16 -1 (-3975 5250)(-3975 5300);
WIRE 16 -1 (-4250 5250)(-3975 5250);
WIRE 16 -1 (-3975 4875)(-3975 5250);
WIRE 16 -1 (-3900 4875)(-3975 4875);
WIRE 16 -1 (-4250 5200)(-4250 5250);
WIRE 16 -1 (-2725 4675)(-2725 4600);
WIRE 16 -1 (-2900 4675)(-2725 4675);
WIRE 16 -1 (-4250 5000)(-4250 4950);
WIRE 16 -1 (-3050 3825)(-3050 3750);
WIRE 16 -1 (-3200 3825)(-3050 3825);
WIRE 16 -1 (-4275 4375)(-4275 4425);
WIRE 16 -1 (-4575 4375)(-4275 4375);
WIRE 16 -1 (-4275 4025)(-4275 4375);
WIRE 16 -1 (-4200 4025)(-4275 4025);
WIRE 16 -1 (-4575 4325)(-4575 4375);
WIRE 16 -1 (-4575 4125)(-4575 4075);
WIRE 16 -1 (-3200 4025)(-2500 4025);
FORCEPROP 2 LAST SIG_NAME CLK_156M_OSC_BRD_CPU1_DN
J 0
(-3060 4035);
DISPLAY 0.617021 (-3060 4035);
PAINT ORANGE (-3060 4035);
WIRE 16 682 (-1600 5425)(-1600 925);
WIRE 16 682 (2525 5425)(-1600 5425);
WIRE 16 682 (-1600 925)(2525 925);
WIRE 16 682 (2525 925)(2525 5425);
WIRE 16 -1 (-2900 4775)(-2200 4775);
FORCEPROP 2 LAST SIG_NAME CLK_156M_OSC_BRD_CPU0_DP
J 0
(-2810 4785);
DISPLAY 0.617021 (-2810 4785);
PAINT ORANGE (-2810 4785);
WIRE 16 -1 (100 1800)(450 1800);
WIRE 16 -1 (100 2000)(100 1800);
WIRE 16 -1 (100 2000)(450 2000);
WIRE 16 -1 (-475 2000)(100 2000);
FORCEPROP 2 LAST SIG_NAME FM_CPU0_VRM_OSC_EN
J 0
(-460 2010);
DISPLAY 0.617021 (-460 2010);
PAINT ORANGE (-460 2010);
WIRE 16 -1 (650 1800)(1650 1800);
FORCEPROP 2 LAST SIG_NAME FM_CPU0_VRM_322M_156M_OSC_EN
J 0
(1000 1810);
DISPLAY 0.617021 (1000 1810);
PAINT ORANGE (1000 1810);
WIRE 16 -1 (650 1300)(975 1300);
WIRE 16 -1 (650 1500)(975 1500);
WIRE 16 -1 (975 1300)(975 1500);
WIRE 16 -1 (975 1500)(1650 1500);
FORCEPROP 2 LAST SIG_NAME FM_CPU1_STL_BRD_OSC_EN
J 0
(1000 1510);
DISPLAY 0.617021 (1000 1510);
PAINT ORANGE (1000 1510);
WIRE 16 -1 (100 1100)(450 1100);
WIRE 16 -1 (100 1300)(100 1100);
WIRE 16 -1 (100 1300)(450 1300);
WIRE 16 -1 (-475 1300)(100 1300);
FORCEPROP 2 LAST SIG_NAME FM_CPU1_VRM_OSC_EN
J 0
(-460 1310);
DISPLAY 0.617021 (-460 1310);
PAINT ORANGE (-460 1310);
WIRE 16 -1 (650 1100)(1650 1100);
FORCEPROP 2 LAST SIG_NAME FM_CPU1_VRM_322M_156M_OSC_EN
J 0
(1000 1110);
DISPLAY 0.617021 (1000 1110);
PAINT ORANGE (1000 1110);
WIRE 16 -1 (625 2925)(950 2925);
WIRE 16 -1 (950 2925)(950 3075);
WIRE 16 -1 (625 3075)(950 3075);
WIRE 16 -1 (1625 3075)(950 3075);
FORCEPROP 2 LAST SIG_NAME CLK_156M_OSC_CPU1_HFI_DP
J 0
(1000 3085);
DISPLAY 0.617021 (1000 3085);
PAINT ORANGE (1000 3085);
WIRE 16 -1 (625 2725)(1625 2725);
FORCEPROP 2 LAST SIG_NAME CLK_322M_OSC_CPU1_RC_DP
J 0
(1000 2735);
DISPLAY 0.617021 (1000 2735);
PAINT ORANGE (1000 2735);
WIRE 3 682 (1000 2450)(900 2450);
WIRE 3 682 (900 2450)(900 2650);
WIRE 3 682 (1000 2650)(1000 2450);
WIRE 3 682 (1000 2650)(900 2650);
WIRE 16 -1 (650 2200)(975 2200);
WIRE 16 -1 (975 2200)(1650 2200);
FORCEPROP 2 LAST SIG_NAME FM_CPU0_STL_BRD_OSC_EN
J 0
(1000 2210);
DISPLAY 0.617021 (1000 2210);
PAINT ORANGE (1000 2210);
WIRE 16 -1 (650 2000)(975 2000);
WIRE 16 -1 (975 2000)(975 2200);
WIRE 16 -1 (-475 2200)(450 2200);
FORCEPROP 2 LAST SIG_NAME FM_156M_CPU0_BRD_OSC_EN
J 0
(-435 2210);
DISPLAY 0.617021 (-435 2210);
PAINT ORANGE (-435 2210);
WIRE 16 -1 (625 4825)(1625 4825);
FORCEPROP 2 LAST SIG_NAME CLK_322M_OSC_CPU0_RC_DN
J 0
(1000 4835);
DISPLAY 0.617021 (1000 4835);
PAINT ORANGE (1000 4835);
WIRE 3 682 (900 4550)(1000 4550);
WIRE 3 682 (900 4750)(900 4550);
WIRE 3 682 (1000 4550)(1000 4750);
WIRE 3 682 (1000 4750)(900 4750);
WIRE 16 -1 (625 4325)(950 4325);
WIRE 16 -1 (625 4475)(950 4475);
WIRE 16 -1 (950 4325)(950 4475);
WIRE 16 -1 (1625 4475)(950 4475);
FORCEPROP 2 LAST SIG_NAME CLK_156M_OSC_CPU0_HFI_DP
J 0
(1000 4485);
DISPLAY 0.617021 (1000 4485);
PAINT ORANGE (1000 4485);
WIRE 16 -1 (625 4125)(1625 4125);
FORCEPROP 2 LAST SIG_NAME CLK_322M_OSC_CPU0_RC_DP
J 0
(1000 4135);
DISPLAY 0.617021 (1000 4135);
PAINT ORANGE (1000 4135);
WIRE 3 682 (900 3850)(1000 3850);
WIRE 3 682 (900 4050)(900 3850);
WIRE 3 682 (1000 3850)(1000 4050);
WIRE 3 682 (1000 4050)(900 4050);
WIRE 16 -1 (625 3625)(950 3625);
WIRE 16 -1 (625 3775)(950 3775);
WIRE 16 -1 (950 3625)(950 3775);
WIRE 16 -1 (1625 3775)(950 3775);
FORCEPROP 2 LAST SIG_NAME CLK_156M_OSC_CPU1_HFI_DN
J 0
(1000 3785);
DISPLAY 0.617021 (1000 3785);
PAINT ORANGE (1000 3785);
WIRE 3 682 (1000 3350)(900 3350);
WIRE 3 682 (1000 3150)(1000 3350);
WIRE 3 682 (900 3350)(900 3150);
WIRE 3 682 (900 3150)(1000 3150);
WIRE 16 -1 (625 3425)(1625 3425);
FORCEPROP 2 LAST SIG_NAME CLK_322M_OSC_CPU1_RC_DN
J 0
(1000 3435);
DISPLAY 0.617021 (1000 3435);
PAINT ORANGE (1000 3435);
WIRE 16 -1 (75 4125)(425 4125);
WIRE 16 -1 (75 4325)(-500 4325);
FORCEPROP 2 LAST SIG_NAME CLK_322M_156M_CPU0_OSC_VRM_DP
J 0
(-500 4335);
DISPLAY 0.617021 (-500 4335);
PAINT ORANGE (-500 4335);
WIRE 16 -1 (75 4325)(75 4125);
WIRE 16 -1 (425 4325)(75 4325);
WIRE 16 -1 (75 4825)(425 4825);
WIRE 16 -1 (75 5025)(75 4825);
WIRE 16 -1 (75 5025)(425 5025);
WIRE 16 -1 (-500 5025)(75 5025);
FORCEPROP 2 LAST SIG_NAME CLK_322M_156M_CPU0_OSC_VRM_DN
J 0
(-500 5035);
DISPLAY 0.617021 (-500 5035);
PAINT ORANGE (-500 5035);
WIRE 16 -1 (625 5025)(950 5025);
WIRE 16 -1 (950 5025)(950 5175);
WIRE 16 -1 (950 5175)(1625 5175);
FORCEPROP 2 LAST SIG_NAME CLK_156M_OSC_CPU0_HFI_DN
J 0
(1000 5185);
DISPLAY 0.617021 (1000 5185);
PAINT ORANGE (1000 5185);
WIRE 16 -1 (625 5175)(950 5175);
WIRE 16 -1 (-500 3775)(425 3775);
FORCEPROP 0 LAST SIG_NAME CLK_156M_OSC_BRD_CPU1_DN
J 0
(-500 3785);
DISPLAY 0.617021 (-500 3785);
PAINT ORANGE (-500 3785);
WIRE 16 -1 (425 4475)(-500 4475);
FORCEPROP 2 LAST SIG_NAME CLK_156M_OSC_BRD_CPU0_DP
J 0
(-500 4485);
DISPLAY 0.617021 (-500 4485);
PAINT ORANGE (-500 4485);
WIRE 16 -1 (425 5175)(-500 5175);
FORCEPROP 2 LAST SIG_NAME CLK_156M_OSC_BRD_CPU0_DN
J 0
(-500 5185);
DISPLAY 0.617021 (-500 5185);
PAINT ORANGE (-500 5185);
WIRE 16 -1 (75 3425)(425 3425);
WIRE 16 -1 (75 3625)(75 3425);
WIRE 16 -1 (75 3625)(425 3625);
WIRE 16 -1 (-500 3625)(75 3625);
FORCEPROP 0 LAST SIG_NAME CLK_322M_156M_CPU1_OSC_VRM_DN
J 0
(-500 3635);
DISPLAY 0.617021 (-500 3635);
PAINT ORANGE (-500 3635);
WIRE 16 -1 (75 2725)(425 2725);
WIRE 16 -1 (75 2925)(75 2725);
WIRE 16 -1 (75 2925)(425 2925);
WIRE 16 -1 (-500 2925)(75 2925);
FORCEPROP 0 LAST SIG_NAME CLK_322M_156M_CPU1_OSC_VRM_DP
J 0
(-500 2935);
DISPLAY 0.617021 (-500 2935);
PAINT ORANGE (-500 2935);
WIRE 16 -1 (-3900 4675)(-4500 4675);
FORCEPROP 2 LAST SIG_NAME NC_CLK_156M_CPU0_OSC
J 0
(-4485 4685);
DISPLAY 0.638298 (-4485 4685);
PAINT ORANGE (-4485 4685);
FORCEPROP 2 LASTPROP $XRERR UNIQUE?
J 0
(-4740 4675);
DISPLAY 0.638298 (-4740 4675);
PAINT MONO (-4740 4675);
DISPLAY INVISIBLE (-4740 4675);
WIRE 16 -1 (-4200 3825)(-4825 3825);
FORCEPROP 2 LAST SIG_NAME NC_CLK_156M_CPU1_OSC
J 0
(-4810 3835);
DISPLAY 0.638298 (-4810 3835);
PAINT ORANGE (-4810 3835);
FORCEPROP 2 LASTPROP $XRERR UNIQUE?
J 0
(-5065 3825);
DISPLAY 0.638298 (-5065 3825);
PAINT MONO (-5065 3825);
DISPLAY INVISIBLE (-5065 3825);
WIRE 16 -1 (-4800 3925)(-4200 3925);
FORCEPROP 2 LAST SIG_NAME FM_CPU1_STL_BRD_OSC_EN
J 0
(-4800 3935);
DISPLAY 0.617021 (-4800 3935);
PAINT ORANGE (-4800 3935);
WIRE 16 -1 (-4475 4775)(-3900 4775);
FORCEPROP 2 LAST SIG_NAME FM_CPU0_STL_BRD_OSC_EN
J 0
(-4475 4785);
DISPLAY 0.617021 (-4475 4785);
PAINT ORANGE (-4475 4785);
WIRE 16 -1 (-500 3075)(425 3075);
FORCEPROP 2 LAST SIG_NAME CLK_156M_OSC_BRD_CPU1_DP
J 0
(-500 3085);
DISPLAY 0.617021 (-500 3085);
PAINT ORANGE (-500 3085);
WIRE 16 -1 (-475 1500)(450 1500);
FORCEPROP 2 LAST SIG_NAME FM_156M_CPU1_BRD_OSC_EN
J 0
(-460 1510);
DISPLAY 0.617021 (-460 1510);
PAINT ORANGE (-460 1510);
WIRE 16 -1 (-2900 4875)(-2200 4875);
FORCEPROP 2 LAST SIG_NAME CLK_156M_OSC_BRD_CPU0_DN
J 0
(-2810 4885);
DISPLAY 0.617021 (-2810 4885);
PAINT ORANGE (-2810 4885);
WIRE 16 -1 (-3200 3925)(-2500 3925);
FORCEPROP 2 LAST SIG_NAME CLK_156M_OSC_BRD_CPU1_DP
J 0
(-3060 3935);
DISPLAY 0.617021 (-3060 3935);
PAINT ORANGE (-3060 3935);
WIRE 16 -1 (-3850 625)(-3375 625);
WIRE 16 -1 (-3375 925)(-3375 625);
WIRE 16 -1 (-3375 625)(-2900 625);
WIRE 16 -1 (-2900 625)(-2350 625);
WIRE 16 -1 (-3375 925)(-2900 925);
WIRE 16 -1 (-2900 925)(-2900 625);
WIRE 16 -1 (-4275 625)(-3850 625);
WIRE 16 -1 (-3850 925)(-3850 625);
WIRE 16 -1 (-3375 925)(-3850 925);
WIRE 16 -1 (-3850 925)(-4275 925);
WIRE 16 -1 (-4275 725)(-4275 625);
WIRE 16 -1 (-2900 925)(-2350 925);
WIRE 16 -1 (-2350 725)(-2350 625);
WIRE 16 -1 (-4275 725)(-2350 725);
WIRE 16 -1 (-2350 825)(-2350 725);
WIRE 16 -1 (-2350 925)(-2350 825);
WIRE 16 -1 (-4275 825)(-4275 725);
WIRE 16 -1 (-4275 925)(-4275 825);
WIRE 16 -1 (-4275 825)(-2350 825);
DOT 1 (950 3075);
DOT 1 (75 5025);
DOT 1 (950 5175);
DOT 1 (75 4325);
DOT 1 (950 4475);
DOT 1 (75 3625);
DOT 1 (75 2925);
DOT 1 (-3975 5250);
DOT 1 (-4275 4375);
DOT 1 (-4275 725);
DOT 1 (-4275 825);
DOT 1 (-3850 625);
DOT 1 (-3850 925);
DOT 1 (-3375 625);
DOT 1 (-3375 925);
DOT 1 (-2900 625);
DOT 1 (-2900 925);
DOT 1 (-2350 725);
DOT 1 (-2350 825);
DOT 1 (100 1300);
DOT 1 (100 2000);
DOT 1 (975 1500);
DOT 1 (975 2200);
DOT 1 (950 3775);
FORCENOTE
ON-BOARD CPU1 STL OSC
(-525 3700) 0;
DISPLAY LEFT (-525 3700);
DISPLAY 0.808511 (-525 3700);
PAINT PURPLE (-525 3700);
FORCENOTE
TP FAB3 POP R7D37 1101
(300 1000) 0;
DISPLAY LEFT (300 1000);
DISPLAY 0.638298 (300 1000);
PAINT RED (300 1000);
FORCENOTE
TP FAB3 POP R7D39 1101
(300 1700) 0;
DISPLAY LEFT (300 1700);
DISPLAY 0.638298 (300 1700);
PAINT RED (300 1700);
FORCENOTE
ENABLE SIGNALS
(250 2350) 0;
DISPLAY LEFT (250 2350);
DISPLAY 1.276596 (250 2350);
PAINT PURPLE (250 2350);
FORCENOTE
CPLD CPU0 STL OSC EN
(-500 2125) 0;
DISPLAY LEFT (-500 2125);
DISPLAY 0.808511 (-500 2125);
PAINT PURPLE (-500 2125);
FORCENOTE
CPLD CPU0 MCP OSC EN
(-500 1925) 0;
DISPLAY LEFT (-500 1925);
DISPLAY 0.808511 (-500 1925);
PAINT PURPLE (-500 1925);
FORCENOTE
TP FAB3 ADD R6W31 0803
(1150 4625) 0;
DISPLAY LEFT (1150 4625);
DISPLAY 0.638298 (1150 4625);
PAINT RED (1150 4625);
FORCENOTE
TP FAB3 RECONNECT R6W31 1012
(1150 4575) 0;
DISPLAY LEFT (1150 4575);
DISPLAY 0.638298 (1150 4575);
PAINT RED (1150 4575);
FORCENOTE
TP FAB3 DELETE R6W31 1019
(1150 4525) 0;
DISPLAY LEFT (1150 4525);
DISPLAY 0.638298 (1150 4525);
PAINT RED (1150 4525);
FORCENOTE
CPU0 MCP
(1700 4025) 0;
DISPLAY LEFT (1700 4025);
DISPLAY 0.808511 (1700 4025);
PAINT PURPLE (1700 4025);
FORCENOTE
TP FAB3 ADD R6W32 0803
(1150 3925) 0;
DISPLAY LEFT (1150 3925);
DISPLAY 0.638298 (1150 3925);
PAINT RED (1150 3925);
FORCENOTE
CPU0 MCP
(1700 4725) 0;
DISPLAY LEFT (1700 4725);
DISPLAY 0.808511 (1700 4725);
PAINT PURPLE (1700 4725);
FORCENOTE
CPU0 STL
(1700 5050) 0;
DISPLAY LEFT (1700 5050);
DISPLAY 0.808511 (1700 5050);
PAINT PURPLE (1700 5050);
FORCENOTE
TP FAB3 RECONNECT R6W32 1012
(1150 3875) 0;
DISPLAY LEFT (1150 3875);
DISPLAY 0.638298 (1150 3875);
PAINT RED (1150 3875);
FORCENOTE
CPU1 STL
(1700 3650) 0;
DISPLAY LEFT (1700 3650);
DISPLAY 0.808511 (1700 3650);
PAINT PURPLE (1700 3650);
FORCENOTE
CPU1 MCP
(1700 3325) 0;
DISPLAY LEFT (1700 3325);
DISPLAY 0.808511 (1700 3325);
PAINT PURPLE (1700 3325);
FORCENOTE
TP FAB3 DELETE R6W32 1019
(1150 3825) 0;
DISPLAY LEFT (1150 3825);
DISPLAY 0.638298 (1150 3825);
PAINT RED (1150 3825);
FORCENOTE
TP FAB3 ADD R6W33 0803
(1150 3225) 0;
DISPLAY LEFT (1150 3225);
DISPLAY 0.638298 (1150 3225);
PAINT RED (1150 3225);
FORCENOTE
TP FAB3 RECONNECT R6W33 1012
(1150 3175) 0;
DISPLAY LEFT (1150 3175);
DISPLAY 0.638298 (1150 3175);
PAINT RED (1150 3175);
FORCENOTE
TP FAB3 DELETE R6W33 1019
(1150 3125) 0;
DISPLAY LEFT (1150 3125);
DISPLAY 0.638298 (1150 3125);
PAINT RED (1150 3125);
FORCENOTE
TP FAB3 ADD R6W34 0803
(1150 2525) 0;
DISPLAY LEFT (1150 2525);
DISPLAY 0.638298 (1150 2525);
PAINT RED (1150 2525);
FORCENOTE
TP FAB3 RECONNECT R6W34 1012
(1150 2475) 0;
DISPLAY LEFT (1150 2475);
DISPLAY 0.638298 (1150 2475);
PAINT RED (1150 2475);
FORCENOTE
TP FAB3 DELETE R6W34 1019
(1150 2425) 0;
DISPLAY LEFT (1150 2425);
DISPLAY 0.638298 (1150 2425);
PAINT RED (1150 2425);
FORCENOTE
CPU1 STL
(1700 2950) 0;
DISPLAY LEFT (1700 2950);
DISPLAY 0.808511 (1700 2950);
PAINT PURPLE (1700 2950);
FORCENOTE
SKX OR SKX MCP STEERING OPTIONS
(-1550 5350) 0;
DISPLAY LEFT (-1550 5350);
DISPLAY 1.021277 (-1550 5350);
PAINT PURPLE (-1550 5350);
FORCENOTE
CPU0 VRM
(-475 4925) 0;
DISPLAY LEFT (-475 4925);
DISPLAY 0.808511 (-475 4925);
PAINT PURPLE (-475 4925);
FORCENOTE
ON-BOARD CPU0 STL OSC
(-475 5100) 0;
DISPLAY LEFT (-475 5100);
DISPLAY 0.808511 (-475 5100);
PAINT PURPLE (-475 5100);
FORCENOTE
USE 322MHZ:
(-1550 4600) 0;
DISPLAY LEFT (-1550 4600);
DISPLAY 1.021277 (-1550 4600);
PAINT PURPLE (-1550 4600);
FORCENOTE
POP R6F10, R6F11, R3F5, R3F6
(-1550 4550) 0;
DISPLAY LEFT (-1550 4550);
DISPLAY 1.021277 (-1550 4550);
PAINT PURPLE (-1550 4550);
FORCENOTE
NOPOP R6W31-34
(-1550 4500) 0;
DISPLAY LEFT (-1550 4500);
DISPLAY 1.021277 (-1550 4500);
PAINT PURPLE (-1550 4500);
FORCENOTE
ON-BOARD CPU0 STL OSC
(-525 4400) 0;
DISPLAY LEFT (-525 4400);
DISPLAY 0.808511 (-525 4400);
PAINT PURPLE (-525 4400);
FORCENOTE
CPU0 VRM
(-475 4225) 0;
DISPLAY LEFT (-475 4225);
DISPLAY 0.808511 (-475 4225);
PAINT PURPLE (-475 4225);
FORCENOTE
ON-BOARD CPU0 STL OSC
(1700 2100) 0;
DISPLAY LEFT (1700 2100);
DISPLAY 0.808511 (1700 2100);
PAINT PURPLE (1700 2100);
FORCENOTE
CPU0 STL
(1700 4400) 0;
DISPLAY LEFT (1700 4400);
DISPLAY 0.808511 (1700 4400);
PAINT PURPLE (1700 4400);
FORCENOTE
CPU1 MCP
(1700 2575) 0;
DISPLAY LEFT (1700 2575);
DISPLAY 0.808511 (1700 2575);
PAINT PURPLE (1700 2575);
FORCENOTE
CPU1 VRM
(-500 3550) 0;
DISPLAY LEFT (-500 3550);
DISPLAY 0.808511 (-500 3550);
PAINT PURPLE (-500 3550);
FORCENOTE
ROOM=CLOCK_CPU1_OSC
(-4075 3475) 0;
DISPLAY LEFT (-4075 3475);
DISPLAY 1.021277 (-4075 3475);
PAINT PURPLE (-4075 3475);
FORCENOTE
ON-BOARD CPU1 STL OSC
(-500 3000) 0;
DISPLAY LEFT (-500 3000);
DISPLAY 0.808511 (-500 3000);
PAINT PURPLE (-500 3000);
FORCENOTE
CPU1 VRM
(-500 2850) 0;
DISPLAY LEFT (-500 2850);
DISPLAY 0.808511 (-500 2850);
PAINT PURPLE (-500 2850);
FORCENOTE
ROOM=CLOCK_CPU0_OSC
(-3700 4400) 0;
DISPLAY LEFT (-3700 4400);
DISPLAY 1.021277 (-3700 4400);
PAINT PURPLE (-3700 4400);
FORCENOTE
OSC CHOICE BASED ON CPU
(-4175 950) 0;
DISPLAY LEFT (-4175 950);
DISPLAY 1.276596 (-4175 950);
PAINT PURPLE (-4175 950);
FORCENOTE
SKX MCP
(-4150 650) 0;
DISPLAY LEFT (-4150 650);
DISPLAY 1.021277 (-4150 650);
PAINT PURPLE (-4150 650);
FORCENOTE
SKX
(-4150 750) 0;
DISPLAY LEFT (-4150 750);
DISPLAY 1.021277 (-4150 750);
PAINT PURPLE (-4150 750);
FORCENOTE
CPU
(-4150 850) 0;
DISPLAY LEFT (-4150 850);
DISPLAY 1.021277 (-4150 850);
PAINT PURPLE (-4150 850);
FORCENOTE
322MHZ
(-3800 650) 0;
DISPLAY LEFT (-3800 650);
DISPLAY 1.021277 (-3800 650);
PAINT PURPLE (-3800 650);
FORCENOTE
FREQUENCY
(-3800 850) 0;
DISPLAY LEFT (-3800 850);
DISPLAY 1.021277 (-3800 850);
PAINT PURPLE (-3800 850);
FORCENOTE
156MHZ
(-3800 750) 0;
DISPLAY LEFT (-3800 750);
DISPLAY 1.021277 (-3800 750);
PAINT PURPLE (-3800 750);
FORCENOTE
G63831-004
(-3300 750) 0;
DISPLAY LEFT (-3300 750);
DISPLAY 1.021277 (-3300 750);
PAINT PURPLE (-3300 750);
FORCENOTE
OSC IPN
(-3300 850) 0;
DISPLAY LEFT (-3300 850);
DISPLAY 1.021277 (-3300 850);
PAINT PURPLE (-3300 850);
FORCENOTE
H77101-001
(-3300 650) 0;
DISPLAY LEFT (-3300 650);
DISPLAY 1.021277 (-3300 650);
PAINT PURPLE (-3300 650);
FORCENOTE
N/A
(-2850 750) 0;
DISPLAY LEFT (-2850 750);
DISPLAY 1.021277 (-2850 750);
PAINT PURPLE (-2850 750);
FORCENOTE
COMMENTS
(-2850 850) 0;
DISPLAY LEFT (-2850 850);
DISPLAY 1.021277 (-2850 850);
PAINT PURPLE (-2850 850);
FORCENOTE
DEBUG ONLY
(-2850 650) 0;
DISPLAY LEFT (-2850 650);
DISPLAY 1.021277 (-2850 650);
PAINT PURPLE (-2850 650);
FORCENOTE
FROM CPLD
(-925 1700) 0;
DISPLAY LEFT (-925 1700);
DISPLAY 1.021277 (-925 1700);
PAINT PURPLE (-925 1700);
FORCENOTE
CPLD CPU1 MCP OSC EN
(-500 1225) 0;
DISPLAY LEFT (-500 1225);
DISPLAY 0.808511 (-500 1225);
PAINT PURPLE (-500 1225);
FORCENOTE
CPLD CPU1 STL OSC EN
(-500 1425) 0;
DISPLAY LEFT (-500 1425);
DISPLAY 0.808511 (-500 1425);
PAINT PURPLE (-500 1425);
FORCENOTE
ON-BOARD CPU1 STL OSC
(1725 1400) 0;
DISPLAY LEFT (1725 1400);
DISPLAY 0.808511 (1725 1400);
PAINT PURPLE (1725 1400);
FORCENOTE
CPU0 VRM
(1750 1675) 0;
DISPLAY LEFT (1750 1675);
DISPLAY 0.808511 (1750 1675);
PAINT PURPLE (1750 1675);
FORCENOTE
CPU1 VRM
(1750 975) 0;
DISPLAY LEFT (1750 975);
DISPLAY 0.808511 (1750 975);
PAINT PURPLE (1750 975);
FORCENOTE
322MHZ IS REQUIRED ONLY IF HSSI IS CONFIGURED AS AN ETHERNET.
(-1550 4650) 0;
DISPLAY LEFT (-1550 4650);
DISPLAY 1.021277 (-1550 4650);
PAINT PURPLE (-1550 4650);
FORCENOTE
$CDS_IMAGE|OSC_VRM_topology_0.JPG|2518|2000
(-3600 2225) 0;
DISPLAY LEFT (-3600 2225);
QUIT
